FILE_TYPE = MACRO_DRAWING;
SET COLOR_WIRE YELLOW;
SET COLOR_PROP MONO;
SET COLOR_DOT WHITE;
SET COLOR_ARC YELLOW;
SET COLOR_BODY GREEN;
SET COLOR_NOTE MONO;
SET PROP_DISPLAY VALUE;
SET PAGE_NUMBER P230;
FORCEADD GND..1
(-2025 -1350);
FORCEPROP 3 LASTPIN (-2025 -1300) SIG_NAME GND\g
J 0
(-2015 -1290);
DISPLAY 0.659574 (-2015 -1290);
PAINT MONO (-2015 -1290);
DISPLAY INVISIBLE (-2015 -1290);
FORCEPROP 1 LAST HDL_POWER GND
J 0
(-2025 -1200);
DISPLAY 0.893617 (-2025 -1200);
PAINT GREEN (-2025 -1200);
DISPLAY INVISIBLE (-2025 -1200);
FORCEPROP 1 LAST BODY_TYPE PLUMBING
J 0
(-2070 -1393);
DISPLAY 0.340426 (-2070 -1393);
PAINT GREEN (-2070 -1393);
DISPLAY INVISIBLE (-2070 -1393);
FORCEPROP 1 LAST PATH I1
J 0
(-1950 -1350);
DISPLAY 0.872340 (-1950 -1350);
PAINT AQUA (-1950 -1350);
DISPLAY INVISIBLE (-1950 -1350);
FORCEPROP 2 LAST CDS_LIB mstr_symbols
J 0
(-2025 -1350);
PAINT MONO (-2025 -1350);
DISPLAY INVISIBLE (-2025 -1350);
FORCEPROP 1 LAST SIZE 1B
J 0
(-1950 -1400);
DISPLAY 0.893617 (-1950 -1400);
PAINT GREEN (-1950 -1400);
DISPLAY INVISIBLE (-1950 -1400);
FORCEPROP 1 LAST VOLTAGE 0.0V
J 0
(-2070 -1393);
DISPLAY 0.340426 (-2070 -1393);
PAINT SKYBLUE (-2070 -1393);
DISPLAY INVISIBLE (-2070 -1393);
FORCEADD CAP..1
(-1300 225);
FORCEPROP 1 LAST PACK_TYPE 0603
J 0
(-1250 25);
DISPLAY 0.617021 (-1250 25);
PAINT SKYBLUE (-1250 25);
FORCEPROP 1 LAST PART_NUMBER E15431-003
J 0
(-1250 75);
DISPLAY 0.617021 (-1250 75);
PAINT BLUE (-1250 75);
FORCEPROP 1 LAST MATERIAL X6S
J 0
(-1250 125);
DISPLAY 0.617021 (-1250 125);
PAINT SKYBLUE (-1250 125);
FORCEPROP 1 LAST TOLERANCE 10%
J 0
(-1250 175);
DISPLAY 0.617021 (-1250 175);
PAINT SKYBLUE (-1250 175);
FORCEPROP 1 LAST VOLTAGE 6.3V
J 0
(-1250 225);
DISPLAY 0.617021 (-1250 225);
PAINT SKYBLUE (-1250 225);
FORCEPROP 1 LAST VALUE 4.7UF
J 0
(-1250 275);
DISPLAY 0.617021 (-1250 275);
PAINT SKYBLUE (-1250 275);
FORCEPROP 1 LAST LOCATION C4A7
J 0
(-1250 325);
DISPLAY 0.617021 (-1250 325);
PAINT AQUA (-1250 325);
FORCEPROP 1 LASTPIN (-1300 125) $PN 2
J 0
(-1290 105);
DISPLAY 0.617021 (-1290 105);
PAINT ORANGE (-1290 105);
FORCEPROP 1 LASTPIN (-1300 325) $PN 1
J 0
(-1290 305);
DISPLAY 0.617021 (-1290 305);
PAINT ORANGE (-1290 305);
FORCEPROP 1 LAST PATH I10
J 0
(-1250 375);
DISPLAY 0.978723 (-1250 375);
PAINT WHITE (-1250 375);
DISPLAY INVISIBLE (-1250 375);
FORCEPROP 0 LAST CDS_SEC 1
J 0
(-1250 375);
PAINT MONO (-1250 375);
DISPLAY INVISIBLE (-1250 375);
FORCEPROP 2 LAST CDS_LIB mstr_discrete
J 0
(-1300 225);
PAINT ORANGE (-1300 225);
DISPLAY INVISIBLE (-1300 225);
FORCEPROP 0 LAST ROOM VTT_KLM_PWR_VR
J 0
(-1250 425);
DISPLAY 1.021277 (-1250 425);
PAINT ORANGE (-1250 425);
DISPLAY INVISIBLE (-1250 425);
FORCEPROP 2 LAST CDS_LOCATION C4A7
J 0
(-1250 325);
DISPLAY 0.617021 (-1250 325);
PAINT AQUA (-1250 325);
DISPLAY INVISIBLE (-1250 325);
FORCEPROP 2 LAST SEC 1
J 0
(-1250 425);
DISPLAY 0.680851 (-1250 425);
PAINT MONO (-1250 425);
DISPLAY INVISIBLE (-1250 425);
FORCEPROP 2 LAST SEC_TYPE 0603
J 0
(-1250 425);
DISPLAY 1.021277 (-1250 425);
PAINT ORANGE (-1250 425);
DISPLAY INVISIBLE (-1250 425);
FORCEADD GND..1
(-1200 525);
FORCEPROP 3 LASTPIN (-1200 575) SIG_NAME GND\g
J 0
(-1190 585);
DISPLAY 0.659574 (-1190 585);
PAINT MONO (-1190 585);
DISPLAY INVISIBLE (-1190 585);
FORCEPROP 1 LAST HDL_POWER GND
J 0
(-1200 675);
DISPLAY 0.893617 (-1200 675);
PAINT GREEN (-1200 675);
DISPLAY INVISIBLE (-1200 675);
FORCEPROP 1 LAST BODY_TYPE PLUMBING
J 0
(-1245 482);
DISPLAY 0.340426 (-1245 482);
PAINT GREEN (-1245 482);
DISPLAY INVISIBLE (-1245 482);
FORCEPROP 1 LAST PATH I11
J 0
(-1125 525);
DISPLAY 0.872340 (-1125 525);
PAINT AQUA (-1125 525);
DISPLAY INVISIBLE (-1125 525);
FORCEPROP 1 LAST VOLTAGE 0.0V
J 0
(-1245 482);
DISPLAY 0.340426 (-1245 482);
PAINT SKYBLUE (-1245 482);
DISPLAY INVISIBLE (-1245 482);
FORCEPROP 2 LAST CDS_LIB mstr_symbols
J 0
(-1200 525);
DISPLAY 0.744681 (-1200 525);
PAINT MONO (-1200 525);
DISPLAY INVISIBLE (-1200 525);
FORCEPROP 1 LAST SIZE 1B
J 0
(-1125 475);
DISPLAY 0.893617 (-1125 475);
PAINT GREEN (-1125 475);
DISPLAY INVISIBLE (-1125 475);
FORCEADD CAP..1
(-1200 775);
FORCEPROP 1 LAST PART_NUMBER D97712-011
J 0
(-1150 725);
DISPLAY 0.617021 (-1150 725);
PAINT BLUE (-1150 725);
FORCEPROP 1 LAST TOLERANCE 10%
J 0
(-1150 775);
DISPLAY 0.617021 (-1150 775);
PAINT SKYBLUE (-1150 775);
FORCEPROP 1 LAST VALUE 1.0UF
J 0
(-1150 825);
DISPLAY 0.617021 (-1150 825);
PAINT SKYBLUE (-1150 825);
FORCEPROP 1 LAST MATERIAL X6S
J 0
(-1025 775);
DISPLAY 0.617021 (-1025 775);
PAINT SKYBLUE (-1025 775);
FORCEPROP 1 LAST VOLTAGE 16V
J 0
(-1000 825);
DISPLAY 0.617021 (-1000 825);
PAINT SKYBLUE (-1000 825);
FORCEPROP 1 LASTPIN (-1200 875) $PN 1
J 0
(-1190 855);
DISPLAY 0.617021 (-1190 855);
PAINT WHITE (-1190 855);
FORCEPROP 1 LASTPIN (-1200 675) $PN 2
J 0
(-1190 655);
DISPLAY 0.617021 (-1190 655);
PAINT WHITE (-1190 655);
FORCEPROP 1 LAST PACK_TYPE 0402
J 0
(-1150 675);
DISPLAY 0.617021 (-1150 675);
PAINT SKYBLUE (-1150 675);
FORCEPROP 1 LAST LOCATION C4A8
J 0
(-1150 875);
DISPLAY 0.617021 (-1150 875);
PAINT AQUA (-1150 875);
FORCEPROP 1 LAST PATH I12
J 0
(-1150 925);
DISPLAY 0.978723 (-1150 925);
PAINT WHITE (-1150 925);
DISPLAY INVISIBLE (-1150 925);
FORCEPROP 0 LAST CDS_SEC 1
J 0
(-1150 925);
PAINT MONO (-1150 925);
DISPLAY INVISIBLE (-1150 925);
FORCEPROP 2 LAST CDS_LIB mstr_discrete
J 0
(-1200 775);
PAINT ORANGE (-1200 775);
DISPLAY INVISIBLE (-1200 775);
FORCEPROP 2 LAST ROOM VTT_KLM_PWR_VR
J 0
(-1150 925);
DISPLAY 1.021277 (-1150 925);
PAINT ORANGE (-1150 925);
DISPLAY INVISIBLE (-1150 925);
FORCEPROP 2 LAST CDS_LOCATION C4A8
J 0
(-1150 875);
DISPLAY 0.617021 (-1150 875);
PAINT AQUA (-1150 875);
DISPLAY INVISIBLE (-1150 875);
FORCEPROP 2 LAST SEC 1
J 0
(-1150 971);
DISPLAY 0.680851 (-1150 971);
PAINT MONO (-1150 971);
DISPLAY INVISIBLE (-1150 971);
FORCEPROP 2 LAST BOM_COST MEM_VRD_VTT_KLM
J 0
(-1150 975);
DISPLAY 1.021277 (-1150 975);
PAINT ORANGE (-1150 975);
DISPLAY INVISIBLE (-1150 975);
FORCEPROP 2 LAST SEC_TYPE 0402
J 0
(-1150 971);
DISPLAY 1.021277 (-1150 971);
PAINT ORANGE (-1150 971);
DISPLAY INVISIBLE (-1150 971);
FORCEADD RES..1
(-1525 1025);
FORCEPROP 1 LAST PACK_TYPE 0402
J 0
(-1600 825);
DISPLAY 0.617021 (-1600 825);
PAINT SKYBLUE (-1600 825);
FORCEPROP 1 LAST MATERIAL CHIP
J 0
(-1525 875);
DISPLAY 0.617021 (-1525 875);
PAINT SKYBLUE (-1525 875);
FORCEPROP 1 LAST WATTAGE 1/16W
J 2
(-1550 875);
DISPLAY 0.617021 (-1550 875);
PAINT SKYBLUE (-1550 875);
FORCEPROP 1 LAST VALUE 0.0
J 2
(-1550 925);
DISPLAY 0.617021 (-1550 925);
PAINT SKYBLUE (-1550 925);
FORCEPROP 1 LAST TOLERANCE 5%
J 0
(-1525 925);
DISPLAY 0.617021 (-1525 925);
PAINT SKYBLUE (-1525 925);
FORCEPROP 1 LAST PART_NUMBER G21497-005
J 0
(-1650 975);
DISPLAY 0.617021 (-1650 975);
PAINT BLUE (-1650 975);
FORCEPROP 1 LASTPIN (-1625 1025) $PN 1
J 0
(-1613 1037);
DISPLAY 0.617021 (-1613 1037);
PAINT WHITE (-1613 1037);
FORCEPROP 1 LASTPIN (-1425 1025) $PN 2
J 0
(-1463 1037);
DISPLAY 0.617021 (-1463 1037);
PAINT WHITE (-1463 1037);
FORCEPROP 1 LAST LOCATION R6L8
J 0
(-1575 1075);
DISPLAY 0.617021 (-1575 1075);
PAINT AQUA (-1575 1075);
FORCEPROP 1 LAST PATH I13
J 0
(-1575 1175);
DISPLAY 0.978723 (-1575 1175);
PAINT WHITE (-1575 1175);
DISPLAY INVISIBLE (-1575 1175);
FORCEPROP 0 LAST CDS_SEC 1
J 0
(-1575 1125);
PAINT MONO (-1575 1125);
DISPLAY INVISIBLE (-1575 1125);
FORCEPROP 2 LAST CDS_LIB mstr_discrete
J 0
(-1525 1025);
DISPLAY 0.744681 (-1525 1025);
PAINT MONO (-1525 1025);
DISPLAY INVISIBLE (-1525 1025);
FORCEPROP 2 LAST SEC_TYPE 0402
J 0
(-1559 1225);
DISPLAY 1.021277 (-1559 1225);
PAINT ORANGE (-1559 1225);
DISPLAY INVISIBLE (-1559 1225);
FORCEPROP 2 LAST BOM_COST MEM_VRD_VTT_KLM
J 0
(-1565 1160);
DISPLAY 1.021277 (-1565 1160);
PAINT ORANGE (-1565 1160);
DISPLAY INVISIBLE (-1565 1160);
FORCEPROP 2 LAST CDS_LOCATION R6L8
J 0
(-1575 1075);
DISPLAY 0.617021 (-1575 1075);
PAINT AQUA (-1575 1075);
DISPLAY INVISIBLE (-1575 1075);
FORCEPROP 2 LAST SEC 1
J 0
(-1559 1225);
DISPLAY 0.680851 (-1559 1225);
PAINT MONO (-1559 1225);
DISPLAY INVISIBLE (-1559 1225);
FORCEPROP 2 LAST ROOM VTT_KLM_PWR_VR
J 0
(-1565 1110);
DISPLAY 1.021277 (-1565 1110);
PAINT ORANGE (-1565 1110);
DISPLAY INVISIBLE (-1565 1110);
FORCEADD GND..1
(350 -150);
FORCEPROP 3 LASTPIN (350 -100) SIG_NAME GND\g
J 0
(360 -90);
DISPLAY 0.659574 (360 -90);
PAINT MONO (360 -90);
DISPLAY INVISIBLE (360 -90);
FORCEPROP 1 LAST HDL_POWER GND
J 0
(350 0);
DISPLAY 0.872340 (350 0);
PAINT GREEN (350 0);
DISPLAY INVISIBLE (350 0);
FORCEPROP 1 LAST BODY_TYPE PLUMBING
J 0
(305 -193);
DISPLAY 0.340426 (305 -193);
PAINT GREEN (305 -193);
DISPLAY INVISIBLE (305 -193);
FORCEPROP 1 LAST PATH I14
J 0
(425 -150);
DISPLAY 0.872340 (425 -150);
PAINT AQUA (425 -150);
DISPLAY INVISIBLE (425 -150);
FORCEPROP 2 LAST CDS_LIB mstr_symbols
J 0
(350 -150);
PAINT ORANGE (350 -150);
DISPLAY INVISIBLE (350 -150);
FORCEPROP 1 LAST VOLTAGE 0.0V
J 0
(305 -193);
DISPLAY 0.340426 (305 -193);
PAINT SKYBLUE (305 -193);
DISPLAY INVISIBLE (305 -193);
FORCEPROP 1 LAST SIZE 1B
J 0
(425 -200);
DISPLAY 0.872340 (425 -200);
PAINT AQUA (425 -200);
DISPLAY INVISIBLE (425 -200);
FORCEADD GND..1
(-1625 1375);
FORCEPROP 3 LASTPIN (-1625 1425) SIG_NAME GND\g
J 0
(-1615 1435);
DISPLAY 0.659574 (-1615 1435);
PAINT MONO (-1615 1435);
DISPLAY INVISIBLE (-1615 1435);
FORCEPROP 1 LAST HDL_POWER GND
J 0
(-1625 1525);
DISPLAY 0.893617 (-1625 1525);
PAINT GREEN (-1625 1525);
DISPLAY INVISIBLE (-1625 1525);
FORCEPROP 1 LAST BODY_TYPE PLUMBING
J 0
(-1670 1332);
DISPLAY 0.340426 (-1670 1332);
PAINT GREEN (-1670 1332);
DISPLAY INVISIBLE (-1670 1332);
FORCEPROP 1 LAST PATH I15
J 0
(-1550 1375);
DISPLAY 0.872340 (-1550 1375);
PAINT AQUA (-1550 1375);
DISPLAY INVISIBLE (-1550 1375);
FORCEPROP 2 LAST BOM_COST MEM_VRD_VTT_KLM
J 0
(-2130 1505);
DISPLAY 1.021277 (-2130 1505);
PAINT ORANGE (-2130 1505);
DISPLAY INVISIBLE (-2130 1505);
FORCEPROP 2 LAST ROOM VTT_KLM_PWR_VR
J 0
(-2130 1455);
DISPLAY 1.021277 (-2130 1455);
PAINT ORANGE (-2130 1455);
DISPLAY INVISIBLE (-2130 1455);
FORCEPROP 1 LAST SIZE 1B
J 0
(-1550 1325);
DISPLAY 0.893617 (-1550 1325);
PAINT GREEN (-1550 1325);
DISPLAY INVISIBLE (-1550 1325);
FORCEPROP 2 LAST CDS_LIB mstr_symbols
J 0
(-1625 1375);
DISPLAY 0.744681 (-1625 1375);
PAINT MONO (-1625 1375);
DISPLAY INVISIBLE (-1625 1375);
FORCEPROP 1 LAST VOLTAGE 0.0V
J 0
(-1670 1332);
DISPLAY 0.340426 (-1670 1332);
PAINT SKYBLUE (-1670 1332);
DISPLAY INVISIBLE (-1670 1332);
FORCEADD GND..1
(-1200 1375);
FORCEPROP 3 LASTPIN (-1200 1425) SIG_NAME GND\g
J 0
(-1190 1435);
DISPLAY 0.659574 (-1190 1435);
PAINT MONO (-1190 1435);
DISPLAY INVISIBLE (-1190 1435);
FORCEPROP 1 LAST HDL_POWER GND
J 0
(-1200 1525);
DISPLAY 0.893617 (-1200 1525);
PAINT GREEN (-1200 1525);
DISPLAY INVISIBLE (-1200 1525);
FORCEPROP 1 LAST BODY_TYPE PLUMBING
J 0
(-1245 1332);
DISPLAY 0.340426 (-1245 1332);
PAINT GREEN (-1245 1332);
DISPLAY INVISIBLE (-1245 1332);
FORCEPROP 1 LAST PATH I16
J 0
(-1125 1375);
DISPLAY 0.872340 (-1125 1375);
PAINT AQUA (-1125 1375);
DISPLAY INVISIBLE (-1125 1375);
FORCEPROP 2 LAST BOM_COST MEM_VRD_VTT_KLM
J 0
(-1705 1505);
DISPLAY 1.021277 (-1705 1505);
PAINT ORANGE (-1705 1505);
DISPLAY INVISIBLE (-1705 1505);
FORCEPROP 2 LAST ROOM VTT_KLM_PWR_VR
J 0
(-1705 1455);
DISPLAY 1.021277 (-1705 1455);
PAINT ORANGE (-1705 1455);
DISPLAY INVISIBLE (-1705 1455);
FORCEPROP 2 LAST CDS_LIB mstr_symbols
J 0
(-1200 1375);
PAINT MONO (-1200 1375);
DISPLAY INVISIBLE (-1200 1375);
FORCEPROP 1 LAST VOLTAGE 0.0V
J 0
(-1245 1332);
DISPLAY 0.340426 (-1245 1332);
PAINT SKYBLUE (-1245 1332);
DISPLAY INVISIBLE (-1245 1332);
FORCEPROP 1 LAST SIZE 1B
J 0
(-1125 1325);
DISPLAY 0.893617 (-1125 1325);
PAINT GREEN (-1125 1325);
DISPLAY INVISIBLE (-1125 1325);
FORCEADD CAP..1
(-1200 1650);
FORCEPROP 1 LAST LOCATION C4A15
J 0
(-1150 1750);
DISPLAY 0.617021 (-1150 1750);
PAINT AQUA (-1150 1750);
FORCEPROP 1 LAST PACK_TYPE 0603LF
J 0
(-1150 1450);
DISPLAY 0.617021 (-1150 1450);
PAINT SKYBLUE (-1150 1450);
FORCEPROP 1 LAST PART_NUMBER E15431-001
J 0
(-1150 1500);
DISPLAY 0.617021 (-1150 1500);
PAINT BLUE (-1150 1500);
FORCEPROP 1 LAST MATERIAL X6S
J 0
(-1150 1550);
DISPLAY 0.617021 (-1150 1550);
PAINT SKYBLUE (-1150 1550);
FORCEPROP 1 LAST TOLERANCE 20%
J 0
(-1150 1600);
DISPLAY 0.617021 (-1150 1600);
PAINT SKYBLUE (-1150 1600);
FORCEPROP 1 LAST VOLTAGE 4V
J 0
(-1150 1650);
DISPLAY 0.617021 (-1150 1650);
PAINT SKYBLUE (-1150 1650);
FORCEPROP 1 LAST VALUE 10UF
J 0
(-1150 1700);
DISPLAY 0.617021 (-1150 1700);
PAINT SKYBLUE (-1150 1700);
FORCEPROP 1 LASTPIN (-1200 1550) $PN 2
J 0
(-1190 1530);
DISPLAY 0.617021 (-1190 1530);
PAINT WHITE (-1190 1530);
FORCEPROP 1 LASTPIN (-1200 1750) $PN 1
J 0
(-1190 1730);
DISPLAY 0.617021 (-1190 1730);
PAINT WHITE (-1190 1730);
FORCEPROP 1 LAST PATH I17
J 0
(-1150 1800);
DISPLAY 0.978723 (-1150 1800);
PAINT WHITE (-1150 1800);
DISPLAY INVISIBLE (-1150 1800);
FORCEPROP 0 LAST CDS_SEC 1
J 0
(-1150 1800);
PAINT MONO (-1150 1800);
DISPLAY INVISIBLE (-1150 1800);
FORCEPROP 2 LAST CDS_LIB mstr_discrete
J 0
(-1200 1650);
PAINT ORANGE (-1200 1650);
DISPLAY INVISIBLE (-1200 1650);
FORCEPROP 2 LAST CDS_LOCATION C4A15
J 0
(-1150 1750);
DISPLAY 0.617021 (-1150 1750);
PAINT AQUA (-1150 1750);
DISPLAY INVISIBLE (-1150 1750);
FORCEPROP 2 LAST ROOM VTT_KLM_PWR_VR
J 0
(-1150 1800);
DISPLAY 1.021277 (-1150 1800);
PAINT ORANGE (-1150 1800);
DISPLAY INVISIBLE (-1150 1800);
FORCEPROP 2 LAST SEC 1
J 0
(-1144 1865);
DISPLAY 0.680851 (-1144 1865);
PAINT MONO (-1144 1865);
DISPLAY INVISIBLE (-1144 1865);
FORCEPROP 2 LAST SEC_TYPE 0603LF
J 0
(-1144 1865);
DISPLAY 1.021277 (-1144 1865);
PAINT ORANGE (-1144 1865);
DISPLAY INVISIBLE (-1144 1865);
FORCEPROP 2 LAST BOM_COST MEM_VRD_VTT_KLM
J 0
(-1150 1850);
DISPLAY 1.021277 (-1150 1850);
PAINT ORANGE (-1150 1850);
DISPLAY INVISIBLE (-1150 1850);
FORCEADD GND..1
(675 -150);
FORCEPROP 3 LASTPIN (675 -100) SIG_NAME GND\g
J 0
(685 -90);
DISPLAY 0.659574 (685 -90);
PAINT MONO (685 -90);
DISPLAY INVISIBLE (685 -90);
FORCEPROP 1 LAST HDL_POWER GND
J 0
(675 0);
DISPLAY 0.872340 (675 0);
PAINT GREEN (675 0);
DISPLAY INVISIBLE (675 0);
FORCEPROP 1 LAST BODY_TYPE PLUMBING
J 0
(630 -193);
DISPLAY 0.340426 (630 -193);
PAINT GREEN (630 -193);
DISPLAY INVISIBLE (630 -193);
FORCEPROP 1 LAST PATH I18
J 0
(750 -150);
DISPLAY 0.872340 (750 -150);
PAINT AQUA (750 -150);
DISPLAY INVISIBLE (750 -150);
FORCEPROP 2 LAST CDS_LIB mstr_symbols
J 0
(675 -150);
PAINT ORANGE (675 -150);
DISPLAY INVISIBLE (675 -150);
FORCEPROP 1 LAST SIZE 1B
J 0
(750 -200);
DISPLAY 0.872340 (750 -200);
PAINT AQUA (750 -200);
DISPLAY INVISIBLE (750 -200);
FORCEPROP 1 LAST VOLTAGE 0.0V
J 0
(630 -193);
DISPLAY 0.340426 (630 -193);
PAINT SKYBLUE (630 -193);
DISPLAY INVISIBLE (630 -193);
FORCEADD GND..1
(2325 -75);
FORCEPROP 3 LASTPIN (2325 -25) SIG_NAME GND\g
J 0
(2335 -15);
DISPLAY 0.659574 (2335 -15);
PAINT MONO (2335 -15);
DISPLAY INVISIBLE (2335 -15);
FORCEPROP 1 LAST HDL_POWER GND
J 0
(2325 75);
DISPLAY 0.893617 (2325 75);
PAINT GREEN (2325 75);
DISPLAY INVISIBLE (2325 75);
FORCEPROP 1 LAST BODY_TYPE PLUMBING
J 0
(2280 -118);
DISPLAY 0.340426 (2280 -118);
PAINT GREEN (2280 -118);
DISPLAY INVISIBLE (2280 -118);
FORCEPROP 1 LAST PATH I19
J 0
(2400 -75);
DISPLAY 0.872340 (2400 -75);
PAINT AQUA (2400 -75);
DISPLAY INVISIBLE (2400 -75);
FORCEPROP 1 LAST SIZE 1B
J 0
(2400 -125);
DISPLAY 0.893617 (2400 -125);
PAINT GREEN (2400 -125);
DISPLAY INVISIBLE (2400 -125);
FORCEPROP 2 LAST CDS_LIB mstr_symbols
J 0
(2325 -75);
PAINT ORANGE (2325 -75);
DISPLAY INVISIBLE (2325 -75);
FORCEPROP 1 LAST VOLTAGE 0.0V
J 0
(2280 -118);
DISPLAY 0.340426 (2280 -118);
PAINT SKYBLUE (2280 -118);
DISPLAY INVISIBLE (2280 -118);
FORCEADD CAP..1
R 2
(-2025 -1125);
FORCEPROP 1 LAST PART_NUMBER A36096-046
J 2
(-2075 -1275);
DISPLAY 0.659574 (-2075 -1275);
PAINT BLUE (-2075 -1275);
FORCEPROP 1 LAST MATERIAL EMPTY
J 2
(-2075 -1225);
DISPLAY 0.617021 (-2075 -1225);
PAINT RED (-2075 -1225);
FORCEPROP 1 LAST PACK_TYPE 0402LF
J 2
(-2125 -1175);
DISPLAY 0.617021 (-2125 -1175);
PAINT SKYBLUE (-2125 -1175);
FORCEPROP 1 LAST LOCATION C4A6
J 2
(-2075 -1025);
DISPLAY 0.617021 (-2075 -1025);
PAINT AQUA (-2075 -1025);
FORCEPROP 1 LASTPIN (-2025 -1225) $PN 2
J 2
(-2035 -1245);
DISPLAY 0.617021 (-2035 -1245);
PAINT WHITE (-2035 -1245);
FORCEPROP 1 LASTPIN (-2025 -1025) $PN 1
J 2
(-2035 -1045);
DISPLAY 0.617021 (-2035 -1045);
PAINT WHITE (-2035 -1045);
FORCEPROP 1 LAST TOLERANCE 10%
J 2
(-2225 -1125);
DISPLAY 0.617021 (-2225 -1125);
PAINT SKYBLUE (-2225 -1125);
FORCEPROP 1 LAST VOLTAGE 50V
J 2
(-2125 -1125);
DISPLAY 0.617021 (-2125 -1125);
PAINT SKYBLUE (-2125 -1125);
FORCEPROP 1 LAST VALUE 1000PF
J 2
(-2075 -1075);
DISPLAY 0.617021 (-2075 -1075);
PAINT SKYBLUE (-2075 -1075);
FORCEPROP 1 LAST PATH I2
J 2
(-2075 -975);
DISPLAY 0.978723 (-2075 -975);
PAINT WHITE (-2075 -975);
DISPLAY INVISIBLE (-2075 -975);
FORCEPROP 0 LAST CDS_SEC 1
J 0
(-2075 -975);
PAINT MONO (-2075 -975);
DISPLAY INVISIBLE (-2075 -975);
FORCEPROP 2 LAST CDS_LIB mstr_discrete
J 0
(-2025 -1125);
PAINT ORANGE (-2025 -1125);
DISPLAY INVISIBLE (-2025 -1125);
FORCEPROP 2 LAST CDS_LOCATION C4A6
J 2
(-2075 -1025);
DISPLAY 0.617021 (-2075 -1025);
PAINT AQUA (-2075 -1025);
DISPLAY INVISIBLE (-2075 -1025);
FORCEPROP 2 LAST BOM_COST MEM_VRD_VTT_KLM
J 0
(-2060 -920);
DISPLAY 1.021277 (-2060 -920);
PAINT ORANGE (-2060 -920);
DISPLAY INVISIBLE (-2060 -920);
FORCEPROP 2 LAST SEC_TYPE 0402LF
J 0
(-2054 -905);
DISPLAY 1.021277 (-2054 -905);
PAINT ORANGE (-2054 -905);
DISPLAY INVISIBLE (-2054 -905);
FORCEPROP 2 LAST SEC 1
J 0
(-2054 -905);
DISPLAY 0.680851 (-2054 -905);
PAINT MONO (-2054 -905);
DISPLAY INVISIBLE (-2054 -905);
FORCEPROP 2 LAST ROOM VTT_KLM_PWR_VR
J 0
(-2060 -970);
DISPLAY 1.021277 (-2060 -970);
PAINT ORANGE (-2060 -970);
DISPLAY INVISIBLE (-2060 -970);
FORCEADD CAP..1
(2325 300);
FORCEPROP 0 LAST GROUP PWR_MLCC_CAP
J 0
(2381 87);
DISPLAY 0.638298 (2381 87);
PAINT BROWN (2381 87);
DISPLAY BOTH (2381 87);
FORCEPROP 1 LAST PART_NUMBER C95333-002
R 1
J 0
(2275 150);
DISPLAY 0.617021 (2275 150);
PAINT BLUE (2275 150);
FORCEPROP 1 LAST PACK_TYPE 0805LF
J 0
(2375 150);
DISPLAY 0.617021 (2375 150);
PAINT SKYBLUE (2375 150);
FORCEPROP 1 LAST MATERIAL X6S
J 0
(2375 200);
DISPLAY 0.617021 (2375 200);
PAINT SKYBLUE (2375 200);
FORCEPROP 1 LAST TOLERANCE 20%
J 0
(2375 250);
DISPLAY 0.617021 (2375 250);
PAINT SKYBLUE (2375 250);
FORCEPROP 1 LAST VALUE 22UF
J 0
(2375 350);
DISPLAY 0.617021 (2375 350);
PAINT SKYBLUE (2375 350);
FORCEPROP 1 LASTPIN (2325 200) $PN 2
J 0
(2335 180);
DISPLAY 0.617021 (2335 180);
PAINT WHITE (2335 180);
FORCEPROP 1 LASTPIN (2325 400) $PN 1
J 0
(2335 380);
DISPLAY 0.617021 (2335 380);
PAINT WHITE (2335 380);
FORCEPROP 1 LAST VOLTAGE 4V
J 0
(2375 300);
DISPLAY 0.617021 (2375 300);
PAINT SKYBLUE (2375 300);
FORCEPROP 1 LAST LOCATION C4A13
J 0
(2375 400);
DISPLAY 0.617021 (2375 400);
PAINT AQUA (2375 400);
FORCEPROP 1 LAST PATH I20
J 0
(2375 450);
DISPLAY 0.978723 (2375 450);
PAINT WHITE (2375 450);
DISPLAY INVISIBLE (2375 450);
FORCEPROP 0 LAST CDS_SEC 1
J 0
(2375 450);
PAINT MONO (2375 450);
DISPLAY INVISIBLE (2375 450);
FORCEPROP 2 LAST CDS_LIB mstr_discrete
J 0
(2325 300);
PAINT ORANGE (2325 300);
DISPLAY INVISIBLE (2325 300);
FORCEPROP 2 LAST CDS_LOCATION C4A13
J 0
(2375 400);
DISPLAY 0.617021 (2375 400);
PAINT AQUA (2375 400);
DISPLAY INVISIBLE (2375 400);
FORCEPROP 2 LAST ROOM VTT_KLM_PWR_VR
J 0
(2395 455);
DISPLAY 1.021277 (2395 455);
PAINT ORANGE (2395 455);
DISPLAY INVISIBLE (2395 455);
FORCEPROP 2 LAST SEC_TYPE 0805LF
J 0
(2376 520);
DISPLAY 1.021277 (2376 520);
PAINT ORANGE (2376 520);
DISPLAY INVISIBLE (2376 520);
FORCEPROP 2 LAST BOM_COST MEM_VRD_VTT_KLM
J 0
(2395 505);
DISPLAY 1.021277 (2395 505);
PAINT ORANGE (2395 505);
DISPLAY INVISIBLE (2395 505);
FORCEPROP 2 LAST SEC 1
J 0
(2376 520);
DISPLAY 0.680851 (2376 520);
PAINT MONO (2376 520);
DISPLAY INVISIBLE (2376 520);
FORCEADD RES..2
R 2
(1800 1250);
FORCEPROP 1 LAST PACK_TYPE 0402
J 2
(1760 1075);
DISPLAY 0.617021 (1760 1075);
PAINT SKYBLUE (1760 1075);
FORCEPROP 1 LAST PART_NUMBER G21796-016
J 2
(1760 1125);
DISPLAY 0.617021 (1760 1125);
PAINT BLUE (1760 1125);
FORCEPROP 1 LAST MATERIAL CHIP
J 2
(1760 1175);
DISPLAY 0.617021 (1760 1175);
PAINT SKYBLUE (1760 1175);
FORCEPROP 1 LAST WATTAGE 1/16W
J 2
(1760 1225);
DISPLAY 0.617021 (1760 1225);
PAINT SKYBLUE (1760 1225);
FORCEPROP 1 LAST TOLERANCE 1%
J 2
(1755 1275);
DISPLAY 0.617021 (1755 1275);
PAINT SKYBLUE (1755 1275);
FORCEPROP 1 LASTPIN (1800 1350) $PN 1
J 2
(1795 1312);
DISPLAY 0.617021 (1795 1312);
PAINT WHITE (1795 1312);
FORCEPROP 1 LAST LOCATION R4A5
J 2
(1755 1375);
DISPLAY 0.617021 (1755 1375);
PAINT AQUA (1755 1375);
FORCEPROP 1 LAST VALUE 10.0K
J 2
(1755 1325);
DISPLAY 0.617021 (1755 1325);
PAINT SKYBLUE (1755 1325);
FORCEPROP 1 LASTPIN (1800 1150) $PN 2
J 2
(1795 1160);
DISPLAY 0.617021 (1795 1160);
PAINT WHITE (1795 1160);
FORCEPROP 1 LAST PATH I21
J 2
(1750 1425);
DISPLAY 0.978723 (1750 1425);
PAINT WHITE (1750 1425);
DISPLAY INVISIBLE (1750 1425);
FORCEPROP 0 LAST CDS_SEC 1
J 0
(1775 1425);
PAINT MONO (1775 1425);
DISPLAY INVISIBLE (1775 1425);
FORCEPROP 2 LAST SEC_TYPE 0402
J 2
(1750 1471);
DISPLAY 1.021277 (1750 1471);
PAINT ORANGE (1750 1471);
DISPLAY INVISIBLE (1750 1471);
FORCEPROP 2 LAST BOM_COST MEM_VRD_VTT_KLM
J 2
(1750 1475);
DISPLAY 1.021277 (1750 1475);
PAINT ORANGE (1750 1475);
DISPLAY INVISIBLE (1750 1475);
FORCEPROP 2 LAST SEC 1
J 2
(1750 1471);
DISPLAY 0.680851 (1750 1471);
PAINT MONO (1750 1471);
DISPLAY INVISIBLE (1750 1471);
FORCEPROP 2 LAST CDS_LOCATION R4A5
J 2
(1755 1375);
DISPLAY 0.617021 (1755 1375);
PAINT AQUA (1755 1375);
DISPLAY INVISIBLE (1755 1375);
FORCEPROP 2 LAST ROOM VTT_KLM_PWR_VR
J 2
(1750 1425);
DISPLAY 1.021277 (1750 1425);
PAINT ORANGE (1750 1425);
DISPLAY INVISIBLE (1750 1425);
FORCEPROP 2 LAST CDS_LIB mstr_discrete
J 2
(1800 1250);
PAINT ORANGE (1800 1250);
DISPLAY INVISIBLE (1800 1250);
FORCEADD GND..1
(2200 650);
FORCEPROP 3 LASTPIN (2200 700) SIG_NAME GND\g
J 0
(2210 710);
DISPLAY 0.659574 (2210 710);
PAINT MONO (2210 710);
DISPLAY INVISIBLE (2210 710);
FORCEPROP 1 LAST HDL_POWER GND
J 0
(2200 800);
DISPLAY 0.893617 (2200 800);
PAINT GREEN (2200 800);
DISPLAY INVISIBLE (2200 800);
FORCEPROP 1 LAST BODY_TYPE PLUMBING
J 0
(2155 607);
DISPLAY 0.340426 (2155 607);
PAINT GREEN (2155 607);
DISPLAY INVISIBLE (2155 607);
FORCEPROP 1 LAST PATH I22
J 0
(2275 650);
DISPLAY 0.872340 (2275 650);
PAINT AQUA (2275 650);
DISPLAY INVISIBLE (2275 650);
FORCEPROP 1 LAST VOLTAGE 0.0V
J 0
(2155 607);
DISPLAY 0.340426 (2155 607);
PAINT SKYBLUE (2155 607);
DISPLAY INVISIBLE (2155 607);
FORCEPROP 2 LAST CDS_LIB mstr_symbols
J 0
(2200 650);
DISPLAY 0.744681 (2200 650);
PAINT MONO (2200 650);
DISPLAY INVISIBLE (2200 650);
FORCEPROP 1 LAST SIZE 1B
J 0
(2275 600);
DISPLAY 0.893617 (2275 600);
PAINT GREEN (2275 600);
DISPLAY INVISIBLE (2275 600);
FORCEADD CAP..1
R 2
(2200 900);
FORCEPROP 1 LAST PACK_TYPE 0402LF
J 2
(2150 700);
DISPLAY 0.617021 (2150 700);
PAINT SKYBLUE (2150 700);
FORCEPROP 1 LAST PART_NUMBER A36096-046
J 2
(2150 750);
DISPLAY 0.617021 (2150 750);
PAINT BLUE (2150 750);
FORCEPROP 1 LAST MATERIAL X7R
J 2
(2150 800);
DISPLAY 0.617021 (2150 800);
PAINT SKYBLUE (2150 800);
FORCEPROP 1 LAST TOLERANCE 10%
J 2
(2150 850);
DISPLAY 0.617021 (2150 850);
PAINT SKYBLUE (2150 850);
FORCEPROP 1 LAST VOLTAGE 50V
J 2
(2150 900);
DISPLAY 0.617021 (2150 900);
PAINT SKYBLUE (2150 900);
FORCEPROP 1 LAST VALUE 1000PF
J 2
(2150 950);
DISPLAY 0.617021 (2150 950);
PAINT SKYBLUE (2150 950);
FORCEPROP 1 LAST LOCATION C4A3
J 2
(2150 1000);
DISPLAY 0.617021 (2150 1000);
PAINT AQUA (2150 1000);
FORCEPROP 1 LASTPIN (2200 800) $PN 2
J 2
(2190 780);
DISPLAY 0.617021 (2190 780);
PAINT WHITE (2190 780);
FORCEPROP 1 LASTPIN (2200 1000) $PN 1
J 2
(2190 980);
DISPLAY 0.617021 (2190 980);
PAINT WHITE (2190 980);
FORCEPROP 1 LAST PATH I23
J 2
(2150 1050);
DISPLAY 0.978723 (2150 1050);
PAINT WHITE (2150 1050);
DISPLAY INVISIBLE (2150 1050);
FORCEPROP 0 LAST CDS_SEC 1
J 0
(2150 1050);
PAINT MONO (2150 1050);
DISPLAY INVISIBLE (2150 1050);
FORCEPROP 2 LAST SEC 1
J 2
(2150 1100);
DISPLAY 0.680851 (2150 1100);
PAINT MONO (2150 1100);
DISPLAY INVISIBLE (2150 1100);
FORCEPROP 2 LAST CDS_LOCATION C4A3
J 2
(2150 1000);
DISPLAY 0.617021 (2150 1000);
PAINT AQUA (2150 1000);
DISPLAY INVISIBLE (2150 1000);
FORCEPROP 2 LAST SEC_TYPE 0402LF
J 2
(2150 1100);
DISPLAY 1.021277 (2150 1100);
PAINT ORANGE (2150 1100);
DISPLAY INVISIBLE (2150 1100);
FORCEPROP 2 LAST BOM_COST MEM_VRD_VTT_KLM
J 2
(2150 1100);
DISPLAY 1.021277 (2150 1100);
PAINT ORANGE (2150 1100);
DISPLAY INVISIBLE (2150 1100);
FORCEPROP 2 LAST ROOM VTT_KLM_PWR_VR
J 2
(2150 1050);
DISPLAY 1.021277 (2150 1050);
PAINT ORANGE (2150 1050);
DISPLAY INVISIBLE (2150 1050);
FORCEPROP 2 LAST CDS_LIB mstr_discrete
J 2
(2200 900);
DISPLAY 0.744681 (2200 900);
PAINT MONO (2200 900);
DISPLAY INVISIBLE (2200 900);
FORCEADD CAP_A..1
(1350 2675);
FORCEPROP 1 LAST VOLTAGE 4V
J 0
(1400 2675);
DISPLAY 0.617021 (1400 2675);
PAINT SKYBLUE (1400 2675);
FORCEPROP 1 LAST TOLERANCE 20%
J 0
(1400 2625);
DISPLAY 0.617021 (1400 2625);
PAINT SKYBLUE (1400 2625);
FORCEPROP 1 LAST MATERIAL X5R
J 0
(1400 2575);
DISPLAY 0.617021 (1400 2575);
PAINT SKYBLUE (1400 2575);
FORCEPROP 1 LAST PART_NUMBER 602433-106
J 0
(1400 2525);
DISPLAY 0.617021 (1400 2525);
PAINT BLUE (1400 2525);
FORCEPROP 1 LAST PACK_TYPE 0603V
J 0
(1400 2475);
DISPLAY 0.617021 (1400 2475);
PAINT SKYBLUE (1400 2475);
FORCEPROP 1 LASTPIN (1350 2775) $PN 1
J 0
(1360 2755);
DISPLAY 0.617021 (1360 2755);
PAINT ORANGE (1360 2755);
FORCEPROP 1 LASTPIN (1350 2575) $PN 2
J 0
(1360 2555);
DISPLAY 0.617021 (1360 2555);
PAINT ORANGE (1360 2555);
FORCEPROP 1 LAST VALUE 47UF
J 0
(1400 2725);
DISPLAY 0.617021 (1400 2725);
PAINT SKYBLUE (1400 2725);
FORCEPROP 0 LAST GROUP PWR_MLCC_CAP
J 0
(1381 2337);
DISPLAY 0.638298 (1381 2337);
PAINT BROWN (1381 2337);
DISPLAY BOTH (1381 2337);
FORCEPROP 1 LAST LOCATION C8M12
J 0
(1400 2775);
DISPLAY 0.617021 (1400 2775);
PAINT AQUA (1400 2775);
FORCEPROP 1 LAST PATH I24
J 0
(1400 2825);
DISPLAY 0.978723 (1400 2825);
PAINT WHITE (1400 2825);
DISPLAY INVISIBLE (1400 2825);
FORCEPROP 2 LAST CDS_LIB dev_discrete
J 0
(1350 2675);
PAINT ORANGE (1350 2675);
DISPLAY INVISIBLE (1350 2675);
FORCEPROP 2 LAST CDS_LOCATION C8M12
J 0
(1400 2775);
DISPLAY 0.617021 (1400 2775);
PAINT AQUA (1400 2775);
DISPLAY INVISIBLE (1400 2775);
FORCEPROP 2 LAST CDS_SEC 1
J 0
(1400 2825);
PAINT ORANGE (1400 2825);
DISPLAY INVISIBLE (1400 2825);
FORCEPROP 2 LAST SEC_TYPE 0603V
J 0
(1400 2875);
DISPLAY 1.021277 (1400 2875);
PAINT ORANGE (1400 2875);
DISPLAY INVISIBLE (1400 2875);
FORCEPROP 2 LAST SEC 1
J 0
(1400 2875);
DISPLAY 0.680851 (1400 2875);
PAINT MONO (1400 2875);
DISPLAY INVISIBLE (1400 2875);
FORCEADD PVTT_KLM..1
(1350 2950);
FORCEPROP 3 LASTPIN (1350 2900) SIG_NAME PVTT_KLM\g
J 0
(1360 2910);
DISPLAY 0.659574 (1360 2910);
PAINT MONO (1360 2910);
DISPLAY INVISIBLE (1360 2910);
FORCEPROP 1 LAST HDL_POWER PVTT_KLM
J 1
(1350 3000);
DISPLAY 0.872340 (1350 3000);
PAINT GREEN (1350 3000);
DISPLAY INVISIBLE (1350 3000);
FORCEPROP 1 LAST BODY_TYPE PLUMBING
J 0
(1305 2907);
DISPLAY 0.340426 (1305 2907);
PAINT GREEN (1305 2907);
DISPLAY INVISIBLE (1305 2907);
FORCEPROP 1 LAST PATH I25
J 0
(1400 2975);
DISPLAY 0.872340 (1400 2975);
PAINT AQUA (1400 2975);
DISPLAY INVISIBLE (1400 2975);
FORCEPROP 1 LAST VOLTAGE 0.6V
J 0
(1305 2907);
DISPLAY 0.340426 (1305 2907);
PAINT SKYBLUE (1305 2907);
DISPLAY INVISIBLE (1305 2907);
FORCEPROP 2 LAST CDS_LIB mstr_symbols
J 0
(1350 2950);
PAINT ORANGE (1350 2950);
DISPLAY INVISIBLE (1350 2950);
FORCEPROP 2 LAST ROOM VTT_KLM_PWR_VR
J 0
(1600 3050);
PAINT ORANGE (1600 3050);
DISPLAY INVISIBLE (1600 3050);
FORCEPROP 2 LAST BOM_COST MEM_KLM_VTT_DEF
J 0
(1425 3050);
PAINT MONO (1425 3050);
DISPLAY INVISIBLE (1425 3050);
FORCEADD P3V3..1
(1800 1550);
FORCEPROP 3 LASTPIN (1800 1500) SIG_NAME P3V3\g
J 0
(1810 1510);
DISPLAY 0.659574 (1810 1510);
PAINT MONO (1810 1510);
DISPLAY INVISIBLE (1810 1510);
FORCEPROP 1 LAST HDL_POWER P3V3
J 0
(1475 1425);
DISPLAY 0.872340 (1475 1425);
PAINT ORANGE (1475 1425);
DISPLAY INVISIBLE (1475 1425);
FORCEPROP 1 LAST BODY_TYPE PLUMBING
J 0
(1755 1507);
DISPLAY 0.340426 (1755 1507);
PAINT GREEN (1755 1507);
DISPLAY INVISIBLE (1755 1507);
FORCEPROP 1 LAST PATH I26
J 0
(1845 1552);
DISPLAY 0.340426 (1845 1552);
PAINT GREEN (1845 1552);
DISPLAY INVISIBLE (1845 1552);
FORCEPROP 1 LAST SIZE 1B
J 0
(1845 1572);
DISPLAY 0.340426 (1845 1572);
PAINT GREEN (1845 1572);
DISPLAY INVISIBLE (1845 1572);
FORCEPROP 2 LAST CDS_LIB mstr_symbols
J 0
(1800 1550);
PAINT ORANGE (1800 1550);
DISPLAY INVISIBLE (1800 1550);
FORCEPROP 1 LAST VOLTAGE 3.3V
J 0
(1755 1507);
DISPLAY 0.340426 (1755 1507);
PAINT SKYBLUE (1755 1507);
DISPLAY INVISIBLE (1755 1507);
FORCEADD GND..1
(1350 2350);
FORCEPROP 3 LASTPIN (1350 2400) SIG_NAME GND\g
J 0
(1360 2410);
DISPLAY 0.659574 (1360 2410);
PAINT MONO (1360 2410);
DISPLAY INVISIBLE (1360 2410);
FORCEPROP 1 LAST HDL_POWER GND
J 0
(1350 2500);
DISPLAY 0.893617 (1350 2500);
PAINT GREEN (1350 2500);
DISPLAY INVISIBLE (1350 2500);
FORCEPROP 1 LAST BODY_TYPE PLUMBING
J 0
(1305 2307);
DISPLAY 0.340426 (1305 2307);
PAINT GREEN (1305 2307);
DISPLAY INVISIBLE (1305 2307);
FORCEPROP 1 LAST PATH I27
J 0
(1425 2350);
DISPLAY 0.872340 (1425 2350);
PAINT AQUA (1425 2350);
DISPLAY INVISIBLE (1425 2350);
FORCEPROP 1 LAST SIZE 1B
J 0
(1425 2300);
DISPLAY 0.893617 (1425 2300);
PAINT GREEN (1425 2300);
DISPLAY INVISIBLE (1425 2300);
FORCEPROP 1 LAST VOLTAGE 0.0V
J 0
(1305 2307);
DISPLAY 0.340426 (1305 2307);
PAINT SKYBLUE (1305 2307);
DISPLAY INVISIBLE (1305 2307);
FORCEPROP 2 LAST CDS_LIB mstr_symbols
J 0
(1350 2350);
PAINT ORANGE (1350 2350);
DISPLAY INVISIBLE (1350 2350);
FORCEPROP 2 LAST ROOM VTT_KLM_PWR_VR
J 0
(800 2425);
PAINT ORANGE (800 2425);
DISPLAY INVISIBLE (800 2425);
FORCEPROP 2 LAST BOM_COST MEM_KLM_VTT_DEF
J 0
(1025 2425);
PAINT MONO (1025 2425);
DISPLAY INVISIBLE (1025 2425);
FORCEADD OFFPAGE..1
(-3075 -600);
FORCEPROP 2 LAST $XR0 226 
J 0
(-3327 -600);
DISPLAY 0.638298 (-3327 -600);
PAINT MONO (-3327 -600);
FORCEPROP 1 LAST COMMENT_BODY TRUE
J 0
(-2950 -700);
DISPLAY 0.872340 (-2950 -700);
PAINT GREEN (-2950 -700);
DISPLAY INVISIBLE (-2950 -700);
FORCEPROP 1 LAST OFFPAGE TRUE
J 0
(-2750 -725);
DISPLAY 0.872340 (-2750 -725);
PAINT GREEN (-2750 -725);
DISPLAY INVISIBLE (-2750 -725);
FORCEPROP 2 LAST PATH I3
J 0
(-3325 -550);
DISPLAY 1.021277 (-3325 -550);
PAINT ORANGE (-3325 -550);
DISPLAY INVISIBLE (-3325 -550);
FORCEPROP 2 LAST CDS_LIB mstr_standard
J 0
(-3075 -600);
DISPLAY 0.744681 (-3075 -600);
PAINT MONO (-3075 -600);
DISPLAY INVISIBLE (-3075 -600);
FORCEADD SHUNT..1
(3300 -700);
FORCEPROP 1 LAST PART_NUMBER N_A
J 0
(3225 -790);
DISPLAY 0.617021 (3225 -790);
PAINT BLUE (3225 -790);
FORCEPROP 1 LASTPIN (3150 -700) $PN 1
J 2
(3200 -690);
DISPLAY 0.617021 (3200 -690);
PAINT ORANGE (3200 -690);
FORCEPROP 1 LASTPIN (3450 -700) $PN 2
J 0
(3410 -690);
DISPLAY 0.617021 (3410 -690);
PAINT ORANGE (3410 -690);
FORCEPROP 1 LAST LOCATION SH8L1
J 0
(3275 -650);
DISPLAY 0.617021 (3275 -650);
PAINT AQUA (3275 -650);
FORCEPROP 1 LAST PATH I30
J 0
(3250 -600);
DISPLAY 0.978723 (3250 -600);
PAINT ORANGE (3250 -600);
DISPLAY INVISIBLE (3250 -600);
FORCEPROP 0 LAST CDS_SEC 1
J 0
(3275 -600);
PAINT MONO (3275 -600);
DISPLAY INVISIBLE (3275 -600);
FORCEPROP 0 LAST CDS_LOCATION SH8L1
J 0
(3275 -600);
PAINT MONO (3275 -600);
DISPLAY INVISIBLE (3275 -600);
FORCEPROP 1 LAST PIN_SHORT A:B
J 0
(3225 -950);
DISPLAY 1.021277 (3225 -950);
PAINT ORANGE (3225 -950);
DISPLAY INVISIBLE (3225 -950);
FORCEPROP 1 LAST PACK_TYPE SH0201
J 0
(3240 -885);
DISPLAY 0.978723 (3240 -885);
PAINT SKYBLUE (3240 -885);
DISPLAY INVISIBLE (3240 -885);
FORCEPROP 1 LAST MATERIAL EMPTY
J 0
(3225 -835);
DISPLAY 0.978723 (3225 -835);
PAINT RED (3225 -835);
DISPLAY INVISIBLE (3225 -835);
FORCEPROP 2 LAST CDS_LIB mstr_misc
J 0
(3300 -700);
PAINT ORANGE (3300 -700);
DISPLAY INVISIBLE (3300 -700);
FORCEPROP 0 LAST SEC 1
J 0
(3225 -600);
DISPLAY 0.680851 (3225 -600);
PAINT MONO (3225 -600);
DISPLAY INVISIBLE (3225 -600);
FORCEPROP 2 LAST SEC_TYPE SH0201
J 0
(3250 -550);
DISPLAY 1.021277 (3250 -550);
PAINT ORANGE (3250 -550);
DISPLAY INVISIBLE (3250 -550);
FORCEADD RES..1
(2575 1100);
FORCEPROP 1 LAST PACK_TYPE 0402
J 0
(2825 950);
DISPLAY 0.617021 (2825 950);
PAINT SKYBLUE (2825 950);
FORCEPROP 1 LAST MATERIAL CHIP
J 0
(2575 950);
DISPLAY 0.617021 (2575 950);
PAINT SKYBLUE (2575 950);
FORCEPROP 1 LAST VALUE 33.2
J 2
(2550 1000);
DISPLAY 0.617021 (2550 1000);
PAINT SKYBLUE (2550 1000);
FORCEPROP 1 LAST LOCATION R4A4
J 0
(2525 1150);
DISPLAY 0.617021 (2525 1150);
PAINT AQUA (2525 1150);
FORCEPROP 1 LAST PART_NUMBER G21796-074
J 0
(2525 1200);
DISPLAY 0.617021 (2525 1200);
PAINT BLUE (2525 1200);
FORCEPROP 1 LAST WATTAGE 1/16W
J 2
(2550 950);
DISPLAY 0.617021 (2550 950);
PAINT SKYBLUE (2550 950);
FORCEPROP 1 LASTPIN (2675 1100) $PN 2
J 0
(2637 1112);
DISPLAY 0.617021 (2637 1112);
PAINT ORANGE (2637 1112);
FORCEPROP 1 LAST TOLERANCE 1%
J 0
(2575 1000);
DISPLAY 0.617021 (2575 1000);
PAINT SKYBLUE (2575 1000);
FORCEPROP 1 LASTPIN (2475 1100) $PN 1
J 0
(2487 1112);
DISPLAY 0.617021 (2487 1112);
PAINT ORANGE (2487 1112);
FORCEPROP 1 LAST PATH I32
J 0
(2525 1250);
DISPLAY 0.978723 (2525 1250);
PAINT WHITE (2525 1250);
DISPLAY INVISIBLE (2525 1250);
FORCEPROP 0 LAST CDS_SEC 1
J 0
(2525 1250);
PAINT MONO (2525 1250);
DISPLAY INVISIBLE (2525 1250);
FORCEPROP 2 LAST SEC_TYPE 0402
J 0
(2525 1300);
DISPLAY 1.021277 (2525 1300);
PAINT ORANGE (2525 1300);
DISPLAY INVISIBLE (2525 1300);
FORCEPROP 2 LAST SEC 1
J 0
(2525 1300);
DISPLAY 0.680851 (2525 1300);
PAINT MONO (2525 1300);
DISPLAY INVISIBLE (2525 1300);
FORCEPROP 2 LAST CDS_LIB mstr_discrete
J 0
(2575 1100);
PAINT MONO (2575 1100);
DISPLAY INVISIBLE (2575 1100);
FORCEPROP 2 LAST CDS_LOCATION R4A4
J 0
(2525 1150);
DISPLAY 0.617021 (2525 1150);
PAINT AQUA (2525 1150);
DISPLAY INVISIBLE (2525 1150);
FORCEADD OFFPAGE..2
(3300 1100);
FORCEPROP 2 LAST $XR0 229 
J 0
(3489 1100);
DISPLAY 0.638298 (3489 1100);
PAINT MONO (3489 1100);
FORCEPROP 2 LAST $XR1 190 
J 0
(3609 1100);
DISPLAY 0.638298 (3609 1100);
PAINT MONO (3609 1100);
FORCEPROP 1 LAST COMMENT_BODY TRUE
J 0
(3255 1005);
DISPLAY 0.872340 (3255 1005);
PAINT GREEN (3255 1005);
DISPLAY INVISIBLE (3255 1005);
FORCEPROP 1 LAST OFFPAGE TRUE
J 0
(3625 975);
DISPLAY 0.872340 (3625 975);
PAINT GREEN (3625 975);
DISPLAY INVISIBLE (3625 975);
FORCEPROP 2 LAST PATH I33
J 0
(3625 1150);
DISPLAY 1.021277 (3625 1150);
PAINT ORANGE (3625 1150);
DISPLAY INVISIBLE (3625 1150);
FORCEPROP 2 LAST CDS_LIB mstr_standard
J 0
(3300 1100);
DISPLAY 0.744681 (3300 1100);
PAINT MONO (3300 1100);
DISPLAY INVISIBLE (3300 1100);
FORCEADD PVTT_KLM..1
(3875 850);
FORCEPROP 3 LASTPIN (3875 800) SIG_NAME PVTT_KLM\g
J 0
(3885 810);
DISPLAY 0.659574 (3885 810);
PAINT MONO (3885 810);
DISPLAY INVISIBLE (3885 810);
FORCEPROP 1 LAST HDL_POWER PVTT_KLM
J 1
(3875 900);
DISPLAY 0.872340 (3875 900);
PAINT GREEN (3875 900);
DISPLAY INVISIBLE (3875 900);
FORCEPROP 1 LAST BODY_TYPE PLUMBING
J 0
(3830 807);
DISPLAY 0.340426 (3830 807);
PAINT GREEN (3830 807);
DISPLAY INVISIBLE (3830 807);
FORCEPROP 1 LAST PATH I34
J 0
(3925 875);
DISPLAY 0.872340 (3925 875);
PAINT AQUA (3925 875);
DISPLAY INVISIBLE (3925 875);
FORCEPROP 1 LAST VOLTAGE 0.6V
J 0
(3830 807);
DISPLAY 0.340426 (3830 807);
PAINT SKYBLUE (3830 807);
DISPLAY INVISIBLE (3830 807);
FORCEPROP 2 LAST CDS_LIB mstr_symbols
J 0
(3875 850);
PAINT ORANGE (3875 850);
DISPLAY INVISIBLE (3875 850);
FORCEADD CAP..1
(-1625 1625);
FORCEPROP 1 LAST PART_NUMBER E15431-001
J 0
(-1575 1475);
DISPLAY 0.617021 (-1575 1475);
PAINT BLUE (-1575 1475);
FORCEPROP 1 LAST VALUE 10UF
J 0
(-1575 1675);
DISPLAY 0.617021 (-1575 1675);
PAINT SKYBLUE (-1575 1675);
FORCEPROP 1 LASTPIN (-1625 1525) $PN 2
J 0
(-1615 1505);
DISPLAY 0.617021 (-1615 1505);
PAINT WHITE (-1615 1505);
FORCEPROP 1 LAST MATERIAL X6S
J 0
(-1575 1525);
DISPLAY 0.617021 (-1575 1525);
PAINT SKYBLUE (-1575 1525);
FORCEPROP 1 LASTPIN (-1625 1725) $PN 1
J 0
(-1615 1705);
DISPLAY 0.617021 (-1615 1705);
PAINT WHITE (-1615 1705);
FORCEPROP 1 LAST LOCATION C6L5
J 0
(-1575 1725);
DISPLAY 0.617021 (-1575 1725);
PAINT AQUA (-1575 1725);
FORCEPROP 1 LAST TOLERANCE 20%
J 0
(-1575 1575);
DISPLAY 0.617021 (-1575 1575);
PAINT SKYBLUE (-1575 1575);
FORCEPROP 1 LAST VOLTAGE 4V
J 0
(-1575 1625);
DISPLAY 0.617021 (-1575 1625);
PAINT SKYBLUE (-1575 1625);
FORCEPROP 1 LAST PACK_TYPE 0603LF
J 0
(-1575 1425);
DISPLAY 0.617021 (-1575 1425);
PAINT SKYBLUE (-1575 1425);
FORCEPROP 1 LAST PATH I35
J 0
(-1575 1775);
DISPLAY 0.978723 (-1575 1775);
PAINT WHITE (-1575 1775);
DISPLAY INVISIBLE (-1575 1775);
FORCEPROP 0 LAST CDS_SEC 1
J 0
(-1575 1775);
PAINT MONO (-1575 1775);
DISPLAY INVISIBLE (-1575 1775);
FORCEPROP 2 LAST CDS_LOCATION C6L5
J 0
(-1575 1725);
DISPLAY 0.617021 (-1575 1725);
PAINT AQUA (-1575 1725);
DISPLAY INVISIBLE (-1575 1725);
FORCEPROP 2 LAST CDS_LIB mstr_discrete
J 0
(-1625 1625);
PAINT ORANGE (-1625 1625);
DISPLAY INVISIBLE (-1625 1625);
FORCEPROP 2 LAST ROOM VTT_KLM_PWR_VR
J 0
(-1575 1775);
DISPLAY 1.021277 (-1575 1775);
PAINT ORANGE (-1575 1775);
DISPLAY INVISIBLE (-1575 1775);
FORCEPROP 2 LAST BOM_COST MEM_VRD_VTT_KLM
J 0
(-1575 1825);
DISPLAY 1.021277 (-1575 1825);
PAINT ORANGE (-1575 1825);
DISPLAY INVISIBLE (-1575 1825);
FORCEPROP 2 LAST SEC_TYPE 0603LF
J 0
(-1569 1840);
DISPLAY 1.021277 (-1569 1840);
PAINT ORANGE (-1569 1840);
DISPLAY INVISIBLE (-1569 1840);
FORCEPROP 2 LAST SEC 1
J 0
(-1569 1840);
DISPLAY 0.680851 (-1569 1840);
PAINT MONO (-1569 1840);
DISPLAY INVISIBLE (-1569 1840);
FORCEADD CAP..1
(675 125);
FORCEPROP 1 LAST PART_NUMBER D97712-011
J 0
(725 75);
DISPLAY 0.617021 (725 75);
PAINT BLUE (725 75);
FORCEPROP 1 LAST TOLERANCE 10%
J 0
(725 125);
DISPLAY 0.617021 (725 125);
PAINT SKYBLUE (725 125);
FORCEPROP 1 LAST MATERIAL X6S
J 0
(850 125);
DISPLAY 0.617021 (850 125);
PAINT SKYBLUE (850 125);
FORCEPROP 1 LAST VALUE 1.0UF
J 0
(725 175);
DISPLAY 0.617021 (725 175);
PAINT SKYBLUE (725 175);
FORCEPROP 1 LAST VOLTAGE 16V
J 0
(875 175);
DISPLAY 0.617021 (875 175);
PAINT SKYBLUE (875 175);
FORCEPROP 1 LASTPIN (675 25) $PN 2
J 0
(685 5);
DISPLAY 0.617021 (685 5);
PAINT WHITE (685 5);
FORCEPROP 1 LASTPIN (675 225) $PN 1
J 0
(685 205);
DISPLAY 0.617021 (685 205);
PAINT WHITE (685 205);
FORCEPROP 1 LAST PACK_TYPE 0402
J 0
(725 25);
DISPLAY 0.617021 (725 25);
PAINT SKYBLUE (725 25);
FORCEPROP 1 LAST LOCATION C4A14
J 0
(725 225);
DISPLAY 0.617021 (725 225);
PAINT AQUA (725 225);
FORCEPROP 1 LAST PATH I36
J 0
(725 275);
DISPLAY 0.978723 (725 275);
PAINT WHITE (725 275);
DISPLAY INVISIBLE (725 275);
FORCEPROP 0 LAST CDS_SEC 1
J 0
(725 275);
PAINT MONO (725 275);
DISPLAY INVISIBLE (725 275);
FORCEPROP 2 LAST CDS_LIB mstr_discrete
J 0
(675 125);
PAINT ORANGE (675 125);
DISPLAY INVISIBLE (675 125);
FORCEPROP 2 LAST CDS_LOCATION C4A14
J 0
(725 225);
DISPLAY 0.617021 (725 225);
PAINT AQUA (725 225);
DISPLAY INVISIBLE (725 225);
FORCEPROP 2 LAST SEC_TYPE 0402
J 0
(731 340);
DISPLAY 1.021277 (731 340);
PAINT ORANGE (731 340);
DISPLAY INVISIBLE (731 340);
FORCEPROP 2 LAST BOM_COST MEM_VRD_VTT_KLM
J 0
(725 325);
DISPLAY 1.021277 (725 325);
PAINT ORANGE (725 325);
DISPLAY INVISIBLE (725 325);
FORCEPROP 2 LAST SEC 1
J 0
(731 340);
DISPLAY 0.680851 (731 340);
PAINT MONO (731 340);
DISPLAY INVISIBLE (731 340);
FORCEPROP 2 LAST ROOM VTT_KLM_PWR_VR
J 0
(725 275);
DISPLAY 1.021277 (725 275);
PAINT ORANGE (725 275);
DISPLAY INVISIBLE (725 275);
FORCEADD MIC5166..1
(-100 325);
FORCEPROP 1 LAST LOCATION EU4A2
J 0
(-350 750);
DISPLAY 0.617021 (-350 750);
PAINT AQUA (-350 750);
FORCEPROP 2 LASTPIN (-400 75) $PN 2
J 2
(-410 85);
DISPLAY 0.617021 (-410 85);
PAINT ORANGE (-410 85);
FORCEPROP 1 LAST PART_NUMBER H55101-001
J 0
(-350 -75);
DISPLAY 0.617021 (-350 -75);
PAINT BLUE (-350 -75);
FORCEPROP 2 LASTPIN (-400 225) $PN 6
J 2
(-410 235);
DISPLAY 0.617021 (-410 235);
PAINT ORANGE (-410 235);
FORCEPROP 2 LASTPIN (200 125) $PN 3
J 0
(210 135);
DISPLAY 0.617021 (210 135);
PAINT ORANGE (210 135);
FORCEPROP 2 LASTPIN (200 175) $PN 8
J 0
(210 185);
DISPLAY 0.617021 (210 185);
PAINT ORANGE (210 185);
FORCEPROP 2 LASTPIN (200 25) $PN 11
J 0
(210 35);
DISPLAY 0.617021 (210 35);
PAINT ORANGE (210 35);
FORCEPROP 2 LASTPIN (-400 575) $PN 10
J 2
(-410 585);
DISPLAY 0.617021 (-410 585);
PAINT ORANGE (-410 585);
FORCEPROP 2 LASTPIN (-400 325) $PN 7
J 2
(-410 335);
DISPLAY 0.617021 (-410 335);
PAINT ORANGE (-410 335);
FORCEPROP 1 LAST MATERIAL IC
J 0
(-350 700);
DISPLAY 0.617021 (-350 700);
PAINT SKYBLUE (-350 700);
FORCEPROP 2 LASTPIN (200 275) $PN 5
J 0
(210 285);
DISPLAY 0.617021 (210 285);
PAINT ORANGE (210 285);
FORCEPROP 2 LASTPIN (-400 425) $PN 4
J 2
(-410 435);
DISPLAY 0.617021 (-410 435);
PAINT ORANGE (-410 435);
FORCEPROP 2 LASTPIN (200 575) $PN 9
J 0
(210 585);
DISPLAY 0.617021 (210 585);
PAINT ORANGE (210 585);
FORCEPROP 2 LASTPIN (200 475) $PN 1
J 0
(210 485);
DISPLAY 0.617021 (210 485);
PAINT ORANGE (210 485);
FORCEPROP 1 LAST PATH I37
J 0
(100 700);
PAINT GREEN (100 700);
DISPLAY INVISIBLE (100 700);
FORCEPROP 0 LAST CDS_SEC 1
J 0
(-350 800);
PAINT MONO (-350 800);
DISPLAY INVISIBLE (-350 800);
FORCEPROP 2 LAST CDS_LOCATION EU4A2
J 0
(-350 750);
DISPLAY 0.617021 (-350 750);
PAINT AQUA (-350 750);
DISPLAY INVISIBLE (-350 750);
FORCEPROP 2 LAST ROOM VTT_KLM_PWR_VR
J 0
(-350 784);
DISPLAY 1.021277 (-350 784);
PAINT ORANGE (-350 784);
DISPLAY INVISIBLE (-350 784);
FORCEPROP 2 LAST BOM_COST MEM_VRD_VTT_KLM
J 0
(-350 832);
DISPLAY 1.021277 (-350 832);
PAINT ORANGE (-350 832);
DISPLAY INVISIBLE (-350 832);
FORCEPROP 2 LAST SEC_TYPE DFN
J 0
(-343 793);
DISPLAY 1.021277 (-343 793);
PAINT ORANGE (-343 793);
DISPLAY INVISIBLE (-343 793);
FORCEPROP 2 LAST SEC 1
J 0
(-343 793);
DISPLAY 0.680851 (-343 793);
PAINT MONO (-343 793);
DISPLAY INVISIBLE (-343 793);
FORCEPROP 1 LAST PACK_TYPE DFN
J 0
(-350 800);
PAINT SKYBLUE (-350 800);
DISPLAY INVISIBLE (-350 800);
FORCEPROP 1 LAST CDS_LMAN_SYM_OUTLINE -250,350,250,-350
J 0
(-100 325);
DISPLAY 0.468085 (-100 325);
PAINT GREEN (-100 325);
DISPLAY INVISIBLE (-100 325);
FORCEPROP 2 LAST CDS_LIB mstr_vreg
J 0
(-100 325);
PAINT ORANGE (-100 325);
DISPLAY INVISIBLE (-100 325);
FORCEADD RES..1
(-2225 -600);
FORCEPROP 1 LAST PACK_TYPE 0402
J 0
(-2300 -775);
DISPLAY 0.617021 (-2300 -775);
PAINT SKYBLUE (-2300 -775);
FORCEPROP 1 LAST VALUE 0.0
J 2
(-2250 -700);
DISPLAY 0.617021 (-2250 -700);
PAINT SKYBLUE (-2250 -700);
FORCEPROP 1 LAST TOLERANCE 5%
J 0
(-2225 -700);
DISPLAY 0.617021 (-2225 -700);
PAINT SKYBLUE (-2225 -700);
FORCEPROP 1 LAST LOCATION R4A3
J 0
(-2275 -550);
DISPLAY 0.617021 (-2275 -550);
PAINT AQUA (-2275 -550);
FORCEPROP 1 LAST PART_NUMBER G21497-005
J 0
(-2275 -500);
DISPLAY 0.617021 (-2275 -500);
PAINT BLUE (-2275 -500);
FORCEPROP 1 LASTPIN (-2325 -600) $PN 1
J 0
(-2313 -588);
DISPLAY 0.617021 (-2313 -588);
PAINT WHITE (-2313 -588);
FORCEPROP 1 LASTPIN (-2125 -600) $PN 2
J 0
(-2163 -588);
DISPLAY 0.617021 (-2163 -588);
PAINT WHITE (-2163 -588);
FORCEPROP 1 LAST MATERIAL CHIP
J 0
(-2525 -775);
DISPLAY 0.617021 (-2525 -775);
PAINT SKYBLUE (-2525 -775);
FORCEPROP 1 LAST WATTAGE 1/16W
J 2
(-2375 -700);
DISPLAY 0.617021 (-2375 -700);
PAINT SKYBLUE (-2375 -700);
FORCEPROP 1 LAST PATH I4
J 0
(-2275 -450);
DISPLAY 0.978723 (-2275 -450);
PAINT WHITE (-2275 -450);
DISPLAY INVISIBLE (-2275 -450);
FORCEPROP 0 LAST CDS_SEC 1
J 0
(-2275 -450);
PAINT MONO (-2275 -450);
DISPLAY INVISIBLE (-2275 -450);
FORCEPROP 2 LAST CDS_LIB mstr_discrete
J 0
(-2225 -600);
PAINT ORANGE (-2225 -600);
DISPLAY INVISIBLE (-2225 -600);
FORCEPROP 2 LAST ROOM VTT_KLM_PWR_VR
J 0
(-2255 -445);
DISPLAY 1.021277 (-2255 -445);
PAINT ORANGE (-2255 -445);
DISPLAY INVISIBLE (-2255 -445);
FORCEPROP 2 LAST CDS_LOCATION R4A3
J 0
(-2275 -550);
DISPLAY 0.617021 (-2275 -550);
PAINT AQUA (-2275 -550);
DISPLAY INVISIBLE (-2275 -550);
FORCEPROP 2 LAST SEC 1
J 0
(-2275 -400);
DISPLAY 0.680851 (-2275 -400);
PAINT MONO (-2275 -400);
DISPLAY INVISIBLE (-2275 -400);
FORCEPROP 2 LAST BOM_COST MEM_VRD_VTT_KLM
J 0
(-2255 -395);
DISPLAY 1.021277 (-2255 -395);
PAINT ORANGE (-2255 -395);
DISPLAY INVISIBLE (-2255 -395);
FORCEPROP 2 LAST SEC_TYPE 0402
J 0
(-2275 -400);
DISPLAY 1.021277 (-2275 -400);
PAINT ORANGE (-2275 -400);
DISPLAY INVISIBLE (-2275 -400);
FORCEADD CAP..1
(1750 2675);
FORCEPROP 1 LAST LOCATION C8L3
J 0
(1800 2775);
DISPLAY 0.617021 (1800 2775);
PAINT AQUA (1800 2775);
FORCEPROP 1 LASTPIN (1750 2775) $PN 1
J 0
(1760 2755);
DISPLAY 0.617021 (1760 2755);
PAINT ORANGE (1760 2755);
FORCEPROP 1 LASTPIN (1750 2575) $PN 2
J 0
(1760 2555);
DISPLAY 0.617021 (1760 2555);
PAINT ORANGE (1760 2555);
FORCEPROP 1 LAST TOLERANCE 20%
J 0
(1800 2625);
DISPLAY 0.617021 (1800 2625);
PAINT SKYBLUE (1800 2625);
FORCEPROP 1 LAST VOLTAGE 4V
J 0
(1800 2675);
DISPLAY 0.617021 (1800 2675);
PAINT SKYBLUE (1800 2675);
FORCEPROP 1 LAST VALUE 100UF
J 0
(1800 2725);
DISPLAY 0.617021 (1800 2725);
PAINT SKYBLUE (1800 2725);
FORCEPROP 1 LAST PART_NUMBER 602433-112
J 0
(1800 2575);
DISPLAY 0.617021 (1800 2575);
PAINT BLUE (1800 2575);
FORCEPROP 1 LAST PACK_TYPE 0805
J 0
(1800 2525);
DISPLAY 0.617021 (1800 2525);
PAINT SKYBLUE (1800 2525);
FORCEPROP 0 LAST GROUP PWR_MLCC_CAP
J 0
(1806 2387);
DISPLAY 0.638298 (1806 2387);
PAINT BROWN (1806 2387);
DISPLAY BOTH (1806 2387);
FORCEPROP 0 LAST NEW_MATERIAL X6S
J 0
(1800 2425);
DISPLAY 0.638298 (1800 2425);
PAINT BROWN (1800 2425);
DISPLAY BOTH (1800 2425);
FORCEPROP 0 LAST NEW_PN 078.1071T.M002
J 0
(1808 2478);
DISPLAY 0.638298 (1808 2478);
PAINT BROWN (1808 2478);
DISPLAY BOTH (1808 2478);
FORCEPROP 2 LAST CDS_LOCATION C8L3
J 0
(1800 2775);
DISPLAY 0.617021 (1800 2775);
PAINT AQUA (1800 2775);
DISPLAY INVISIBLE (1800 2775);
FORCEPROP 0 LAST CDS_SEC 1
J 0
(1800 2825);
PAINT MONO (1800 2825);
DISPLAY INVISIBLE (1800 2825);
FORCEPROP 2 LAST CDS_LIB mstr_discrete
J 0
(1750 2675);
PAINT MONO (1750 2675);
DISPLAY INVISIBLE (1750 2675);
FORCEPROP 2 LAST BOM_COST MEM_VRD_PVDDQ_CD
J 0
(1800 2825);
PAINT MONO (1800 2825);
DISPLAY INVISIBLE (1800 2825);
FORCEPROP 2 LAST ROOM VDDQ_ABC_PWR_VR
J 0
(1800 2825);
PAINT MONO (1800 2825);
DISPLAY INVISIBLE (1800 2825);
FORCEPROP 2 LAST SEC_TYPE 0805
J 0
(1800 2875);
DISPLAY 1.021277 (1800 2875);
PAINT ORANGE (1800 2875);
DISPLAY INVISIBLE (1800 2875);
FORCEPROP 2 LAST SEC 1
J 0
(1800 2875);
DISPLAY 0.680851 (1800 2875);
PAINT MONO (1800 2875);
DISPLAY INVISIBLE (1800 2875);
FORCEPROP 1 LAST MATERIAL X5R
J 0
(1800 2575);
DISPLAY 0.617021 (1800 2575);
PAINT SKYBLUE (1800 2575);
DISPLAY INVISIBLE (1800 2575);
FORCEPROP 1 LAST PATH I41
J 0
(1800 2825);
DISPLAY 0.978723 (1800 2825);
PAINT WHITE (1800 2825);
DISPLAY INVISIBLE (1800 2825);
FORCEADD CAP..1
(2150 2675);
FORCEPROP 1 LAST VALUE 100UF
J 0
(2200 2725);
DISPLAY 0.617021 (2200 2725);
PAINT SKYBLUE (2200 2725);
FORCEPROP 1 LAST VOLTAGE 4V
J 0
(2200 2675);
DISPLAY 0.617021 (2200 2675);
PAINT SKYBLUE (2200 2675);
FORCEPROP 1 LAST TOLERANCE 20%
J 0
(2200 2625);
DISPLAY 0.617021 (2200 2625);
PAINT SKYBLUE (2200 2625);
FORCEPROP 1 LASTPIN (2150 2775) $PN 1
J 0
(2160 2755);
DISPLAY 0.617021 (2160 2755);
PAINT ORANGE (2160 2755);
FORCEPROP 1 LAST LOCATION C8L4
J 0
(2200 2775);
DISPLAY 0.617021 (2200 2775);
PAINT AQUA (2200 2775);
FORCEPROP 1 LASTPIN (2150 2575) $PN 2
J 0
(2160 2555);
DISPLAY 0.617021 (2160 2555);
PAINT ORANGE (2160 2555);
FORCEPROP 1 LAST PACK_TYPE 0805
J 0
(2200 2525);
DISPLAY 0.617021 (2200 2525);
PAINT SKYBLUE (2200 2525);
FORCEPROP 0 LAST GROUP PWR_MLCC_CAP
J 0
(2206 2212);
DISPLAY 0.638298 (2206 2212);
PAINT BROWN (2206 2212);
DISPLAY BOTH (2206 2212);
FORCEPROP 1 LAST PART_NUMBER 602433-112
J 0
(2200 2575);
DISPLAY 0.617021 (2200 2575);
PAINT BLUE (2200 2575);
FORCEPROP 0 LAST NEW_MATERIAL X6S
J 0
(2225 2250);
DISPLAY 0.638298 (2225 2250);
PAINT BROWN (2225 2250);
DISPLAY BOTH (2225 2250);
FORCEPROP 0 LAST NEW_PN 078.1071T.M002
J 0
(2202 2309);
DISPLAY 0.638298 (2202 2309);
PAINT BROWN (2202 2309);
DISPLAY BOTH (2202 2309);
FORCEPROP 2 LAST CDS_LOCATION C8L4
J 0
(2200 2775);
DISPLAY 0.617021 (2200 2775);
PAINT AQUA (2200 2775);
DISPLAY INVISIBLE (2200 2775);
FORCEPROP 1 LAST MATERIAL X5R
J 0
(2200 2575);
DISPLAY 0.617021 (2200 2575);
PAINT SKYBLUE (2200 2575);
DISPLAY INVISIBLE (2200 2575);
FORCEPROP 2 LAST SEC 1
J 0
(2200 2875);
DISPLAY 0.680851 (2200 2875);
PAINT MONO (2200 2875);
DISPLAY INVISIBLE (2200 2875);
FORCEPROP 2 LAST SEC_TYPE 0805
J 0
(2200 2875);
DISPLAY 1.021277 (2200 2875);
PAINT ORANGE (2200 2875);
DISPLAY INVISIBLE (2200 2875);
FORCEPROP 2 LAST ROOM VDDQ_ABC_PWR_VR
J 0
(2200 2825);
PAINT MONO (2200 2825);
DISPLAY INVISIBLE (2200 2825);
FORCEPROP 2 LAST BOM_COST MEM_VRD_PVDDQ_CD
J 0
(2200 2825);
PAINT MONO (2200 2825);
DISPLAY INVISIBLE (2200 2825);
FORCEPROP 2 LAST CDS_LIB mstr_discrete
J 0
(2150 2675);
PAINT MONO (2150 2675);
DISPLAY INVISIBLE (2150 2675);
FORCEPROP 0 LAST CDS_SEC 1
J 0
(2200 2825);
PAINT MONO (2200 2825);
DISPLAY INVISIBLE (2200 2825);
FORCEPROP 1 LAST PATH I42
J 0
(2200 2825);
DISPLAY 0.978723 (2200 2825);
PAINT WHITE (2200 2825);
DISPLAY INVISIBLE (2200 2825);
FORCEADD CAP..1
(3125 325);
FORCEPROP 0 LAST NEW_PN 078.1071T.M002
J 0
(3189 114);
DISPLAY 0.638298 (3189 114);
PAINT BROWN (3189 114);
DISPLAY BOTH (3189 114);
FORCEPROP 0 LAST GROUP PWR_MLCC_CAP
J 0
(3181 37);
DISPLAY 0.638298 (3181 37);
PAINT BROWN (3181 37);
DISPLAY BOTH (3181 37);
FORCEPROP 0 LAST NEW_MATERIAL X6S
J 0
(3175 75);
DISPLAY 0.638298 (3175 75);
PAINT BROWN (3175 75);
DISPLAY BOTH (3175 75);
FORCEPROP 1 LAST PART_NUMBER 602433-112
J 0
(3175 225);
DISPLAY 0.617021 (3175 225);
PAINT BLUE (3175 225);
FORCEPROP 1 LAST PACK_TYPE 0805
J 0
(3175 175);
DISPLAY 0.617021 (3175 175);
PAINT SKYBLUE (3175 175);
FORCEPROP 1 LASTPIN (3125 225) $PN 2
J 0
(3135 205);
DISPLAY 0.617021 (3135 205);
PAINT ORANGE (3135 205);
FORCEPROP 1 LAST LOCATION C6W13
J 0
(3175 425);
DISPLAY 0.617021 (3175 425);
PAINT AQUA (3175 425);
FORCEPROP 1 LASTPIN (3125 425) $PN 1
J 0
(3135 405);
DISPLAY 0.617021 (3135 405);
PAINT ORANGE (3135 405);
FORCEPROP 1 LAST TOLERANCE 20%
J 0
(3175 275);
DISPLAY 0.617021 (3175 275);
PAINT SKYBLUE (3175 275);
FORCEPROP 1 LAST VOLTAGE 4V
J 0
(3175 325);
DISPLAY 0.617021 (3175 325);
PAINT SKYBLUE (3175 325);
FORCEPROP 1 LAST VALUE 100UF
J 0
(3175 375);
DISPLAY 0.617021 (3175 375);
PAINT SKYBLUE (3175 375);
FORCEPROP 2 LAST CDS_LOCATION C6W13
J 0
(3175 425);
DISPLAY 0.617021 (3175 425);
PAINT AQUA (3175 425);
DISPLAY INVISIBLE (3175 425);
FORCEPROP 1 LAST PATH I43
J 0
(3175 475);
DISPLAY 0.978723 (3175 475);
PAINT WHITE (3175 475);
DISPLAY INVISIBLE (3175 475);
FORCEPROP 0 LAST CDS_SEC 1
J 0
(3175 475);
PAINT MONO (3175 475);
DISPLAY INVISIBLE (3175 475);
FORCEPROP 2 LAST CDS_LIB mstr_discrete
J 0
(3125 325);
PAINT MONO (3125 325);
DISPLAY INVISIBLE (3125 325);
FORCEPROP 2 LAST BOM_COST MEM_VRD_PVDDQ_CD
J 0
(3175 475);
PAINT MONO (3175 475);
DISPLAY INVISIBLE (3175 475);
FORCEPROP 2 LAST ROOM VDDQ_ABC_PWR_VR
J 0
(3175 475);
PAINT MONO (3175 475);
DISPLAY INVISIBLE (3175 475);
FORCEPROP 2 LAST SEC_TYPE 0805
J 0
(3175 525);
DISPLAY 1.021277 (3175 525);
PAINT ORANGE (3175 525);
DISPLAY INVISIBLE (3175 525);
FORCEPROP 2 LAST SEC 1
J 0
(3175 525);
DISPLAY 0.680851 (3175 525);
PAINT MONO (3175 525);
DISPLAY INVISIBLE (3175 525);
FORCEPROP 1 LAST MATERIAL X5R
J 0
(3175 225);
DISPLAY 0.617021 (3175 225);
PAINT SKYBLUE (3175 225);
DISPLAY INVISIBLE (3175 225);
FORCEADD RES..2
R 2
(-1975 -75);
FORCEPROP 1 LAST PACK_TYPE 0402
J 2
(-2015 -250);
DISPLAY 0.617021 (-2015 -250);
PAINT SKYBLUE (-2015 -250);
FORCEPROP 1 LAST PART_NUMBER G21796-021
J 2
(-2015 -200);
DISPLAY 0.617021 (-2015 -200);
PAINT BLUE (-2015 -200);
FORCEPROP 1 LAST MATERIAL EMPTY
J 2
(-2015 -150);
DISPLAY 0.617021 (-2015 -150);
PAINT RED (-2015 -150);
FORCEPROP 1 LAST WATTAGE 1/16W
J 2
(-2015 -100);
DISPLAY 0.617021 (-2015 -100);
PAINT SKYBLUE (-2015 -100);
FORCEPROP 1 LAST TOLERANCE 1%
J 2
(-2020 -50);
DISPLAY 0.617021 (-2020 -50);
PAINT SKYBLUE (-2020 -50);
FORCEPROP 1 LAST VALUE 1.0M
J 2
(-2020 0);
DISPLAY 0.617021 (-2020 0);
PAINT SKYBLUE (-2020 0);
FORCEPROP 1 LAST LOCATION R6L5
J 2
(-2020 50);
DISPLAY 0.617021 (-2020 50);
PAINT AQUA (-2020 50);
FORCEPROP 1 LASTPIN (-1975 -175) $PN 2
J 2
(-1980 -165);
DISPLAY 0.617021 (-1980 -165);
PAINT WHITE (-1980 -165);
FORCEPROP 1 LASTPIN (-1975 25) $PN 1
J 2
(-1980 -13);
DISPLAY 0.617021 (-1980 -13);
PAINT WHITE (-1980 -13);
FORCEPROP 1 LAST PATH I5
J 2
(-2025 100);
DISPLAY 0.978723 (-2025 100);
PAINT WHITE (-2025 100);
DISPLAY INVISIBLE (-2025 100);
FORCEPROP 0 LAST CDS_SEC 1
J 0
(-2000 100);
PAINT MONO (-2000 100);
DISPLAY INVISIBLE (-2000 100);
FORCEPROP 2 LAST CDS_LIB mstr_discrete
J 0
(-1975 -75);
PAINT ORANGE (-1975 -75);
DISPLAY INVISIBLE (-1975 -75);
FORCEPROP 2 LAST BOM_COST MEM_VRD_VTT_KLM
J 0
(-2010 140);
DISPLAY 1.021277 (-2010 140);
PAINT ORANGE (-2010 140);
DISPLAY INVISIBLE (-2010 140);
FORCEPROP 2 LAST SEC_TYPE 0402
J 0
(-2004 155);
DISPLAY 1.021277 (-2004 155);
PAINT ORANGE (-2004 155);
DISPLAY INVISIBLE (-2004 155);
FORCEPROP 2 LAST SEC 1
J 0
(-2004 155);
DISPLAY 0.680851 (-2004 155);
PAINT MONO (-2004 155);
DISPLAY INVISIBLE (-2004 155);
FORCEPROP 2 LAST CDS_LOCATION R6L5
J 2
(-2020 50);
DISPLAY 0.617021 (-2020 50);
PAINT AQUA (-2020 50);
DISPLAY INVISIBLE (-2020 50);
FORCEPROP 2 LAST ROOM VTT_KLM_PWR_VR
J 0
(-2010 90);
DISPLAY 1.021277 (-2010 90);
PAINT ORANGE (-2010 90);
DISPLAY INVISIBLE (-2010 90);
FORCEADD RES..2
R 1
(-2350 825);
FORCEPROP 1 LAST MATERIAL CHIP
J 0
(-2425 590);
DISPLAY 0.617021 (-2425 590);
PAINT SKYBLUE (-2425 590);
FORCEPROP 1 LAST PART_NUMBER G21497-005
J 0
(-2450 715);
DISPLAY 0.617021 (-2450 715);
PAINT BLUE (-2450 715);
FORCEPROP 1 LAST TOLERANCE 5%
J 0
(-2500 770);
DISPLAY 0.617021 (-2500 770);
PAINT SKYBLUE (-2500 770);
FORCEPROP 1 LAST VALUE 0.0
J 0
(-2425 770);
DISPLAY 0.617021 (-2425 770);
PAINT SKYBLUE (-2425 770);
FORCEPROP 1 LAST WATTAGE 1/16W
J 0
(-2325 765);
DISPLAY 0.617021 (-2325 765);
PAINT SKYBLUE (-2325 765);
FORCEPROP 1 LASTPIN (-2250 825) $PN 2
R 1
J 0
(-2260 830);
DISPLAY 0.617021 (-2260 830);
PAINT WHITE (-2260 830);
FORCEPROP 1 LAST LOCATION R6L6
J 0
(-2375 870);
DISPLAY 0.617021 (-2375 870);
PAINT AQUA (-2375 870);
FORCEPROP 1 LASTPIN (-2450 825) $PN 1
R 1
J 0
(-2412 830);
DISPLAY 0.617021 (-2412 830);
PAINT WHITE (-2412 830);
FORCEPROP 1 LAST PACK_TYPE 0402
J 0
(-2125 765);
DISPLAY 0.617021 (-2125 765);
PAINT SKYBLUE (-2125 765);
FORCEPROP 1 LAST PATH I6
R 1
J 0
(-2525 875);
DISPLAY 0.978723 (-2525 875);
PAINT WHITE (-2525 875);
DISPLAY INVISIBLE (-2525 875);
FORCEPROP 0 LAST CDS_SEC 1
R 1
J 0
(-2375 900);
PAINT MONO (-2375 900);
DISPLAY INVISIBLE (-2375 900);
FORCEPROP 2 LAST CDS_LIB mstr_discrete
R 1
J 0
(-2350 825);
PAINT ORANGE (-2350 825);
DISPLAY INVISIBLE (-2350 825);
FORCEPROP 2 LAST SEC_TYPE 0402
J 0
(-2369 915);
DISPLAY 1.021277 (-2369 915);
PAINT ORANGE (-2369 915);
DISPLAY INVISIBLE (-2369 915);
FORCEPROP 2 LAST BOM_COST MEM_VRD_VTT_KLM
J 0
(-2375 975);
DISPLAY 1.021277 (-2375 975);
PAINT ORANGE (-2375 975);
DISPLAY INVISIBLE (-2375 975);
FORCEPROP 2 LAST CDS_LOCATION R6L6
J 0
(-2375 870);
DISPLAY 0.617021 (-2375 870);
PAINT AQUA (-2375 870);
DISPLAY INVISIBLE (-2375 870);
FORCEPROP 2 LAST NO_XNET_CONNECTION 1
J 0
(-2375 900);
PAINT MONO (-2375 900);
DISPLAY INVISIBLE (-2375 900);
FORCEPROP 2 LAST SEC 1
J 0
(-2369 915);
DISPLAY 0.680851 (-2369 915);
PAINT MONO (-2369 915);
DISPLAY INVISIBLE (-2369 915);
FORCEPROP 2 LAST ROOM VTT_KLM_PWR_VR
J 0
(-2375 925);
DISPLAY 1.021277 (-2375 925);
PAINT ORANGE (-2375 925);
DISPLAY INVISIBLE (-2375 925);
FORCEADD P3V3..1
(-2050 1325);
FORCEPROP 3 LASTPIN (-2050 1275) SIG_NAME P3V3\g
J 0
(-2040 1285);
DISPLAY 0.659574 (-2040 1285);
PAINT MONO (-2040 1285);
DISPLAY INVISIBLE (-2040 1285);
FORCEPROP 1 LAST HDL_POWER P3V3
J 0
(-2375 1200);
DISPLAY 0.872340 (-2375 1200);
PAINT ORANGE (-2375 1200);
DISPLAY INVISIBLE (-2375 1200);
FORCEPROP 1 LAST BODY_TYPE PLUMBING
J 0
(-2095 1282);
DISPLAY 0.340426 (-2095 1282);
PAINT GREEN (-2095 1282);
DISPLAY INVISIBLE (-2095 1282);
FORCEPROP 1 LAST PATH I7
J 0
(-2005 1327);
DISPLAY 0.340426 (-2005 1327);
PAINT GREEN (-2005 1327);
DISPLAY INVISIBLE (-2005 1327);
FORCEPROP 1 LAST VOLTAGE 3.3V
J 0
(-2095 1282);
DISPLAY 0.340426 (-2095 1282);
PAINT SKYBLUE (-2095 1282);
DISPLAY INVISIBLE (-2095 1282);
FORCEPROP 2 LAST CDS_LIB mstr_symbols
J 0
(-2050 1325);
PAINT ORANGE (-2050 1325);
DISPLAY INVISIBLE (-2050 1325);
FORCEPROP 1 LAST SIZE 1B
J 0
(-2005 1347);
DISPLAY 0.340426 (-2005 1347);
PAINT GREEN (-2005 1347);
DISPLAY INVISIBLE (-2005 1347);
FORCEADD PVDDQ_KLM..1
(-3100 2050);
FORCEPROP 3 LASTPIN (-3100 2000) SIG_NAME PVDDQ_KLM\g
J 0
(-3090 2010);
DISPLAY 0.659574 (-3090 2010);
PAINT MONO (-3090 2010);
DISPLAY INVISIBLE (-3090 2010);
FORCEPROP 1 LAST HDL_POWER PVDDQ_KLM
J 1
(-3100 2100);
DISPLAY 0.872340 (-3100 2100);
PAINT GREEN (-3100 2100);
DISPLAY INVISIBLE (-3100 2100);
FORCEPROP 1 LAST BODY_TYPE PLUMBING
J 0
(-3145 2007);
DISPLAY 0.340426 (-3145 2007);
PAINT GREEN (-3145 2007);
DISPLAY INVISIBLE (-3145 2007);
FORCEPROP 1 LAST PATH I8
J 0
(-3050 2075);
DISPLAY 0.872340 (-3050 2075);
PAINT AQUA (-3050 2075);
DISPLAY INVISIBLE (-3050 2075);
FORCEPROP 2 LAST CDS_LIB mstr_symbols
J 0
(-3100 2050);
PAINT ORANGE (-3100 2050);
DISPLAY INVISIBLE (-3100 2050);
FORCEPROP 1 LAST VOLTAGE 1.2V
J 0
(-3145 2007);
DISPLAY 0.340426 (-3145 2007);
PAINT SKYBLUE (-3145 2007);
DISPLAY INVISIBLE (-3145 2007);
FORCEADD GND..1
(-1300 25);
FORCEPROP 3 LASTPIN (-1300 75) SIG_NAME GND\g
J 0
(-1290 85);
DISPLAY 0.659574 (-1290 85);
PAINT MONO (-1290 85);
DISPLAY INVISIBLE (-1290 85);
FORCEPROP 1 LAST HDL_POWER GND
J 0
(-1300 175);
DISPLAY 0.872340 (-1300 175);
PAINT GREEN (-1300 175);
DISPLAY INVISIBLE (-1300 175);
FORCEPROP 1 LAST BODY_TYPE PLUMBING
J 0
(-1345 -18);
DISPLAY 0.340426 (-1345 -18);
PAINT GREEN (-1345 -18);
DISPLAY INVISIBLE (-1345 -18);
FORCEPROP 1 LAST PATH I9
J 0
(-1225 25);
DISPLAY 0.872340 (-1225 25);
PAINT AQUA (-1225 25);
DISPLAY INVISIBLE (-1225 25);
FORCEPROP 1 LAST SIZE 1B
J 0
(-1225 -25);
DISPLAY 0.872340 (-1225 -25);
PAINT AQUA (-1225 -25);
DISPLAY INVISIBLE (-1225 -25);
FORCEPROP 1 LAST VOLTAGE 0.0V
J 0
(-1345 -18);
DISPLAY 0.340426 (-1345 -18);
PAINT SKYBLUE (-1345 -18);
DISPLAY INVISIBLE (-1345 -18);
FORCEPROP 2 LAST CDS_LIB mstr_symbols
J 0
(-1300 25);
PAINT ORANGE (-1300 25);
DISPLAY INVISIBLE (-1300 25);
FORCEADD DNS..2
(-2020 -1130);
PAINT RED (-2020 -1130);
FORCEPROP 1 LAST COMMENT_BODY TRUE
R 1
J 0
(-1945 -1355);
DISPLAY 0.872340 (-1945 -1355);
PAINT GREEN (-1945 -1355);
DISPLAY INVISIBLE (-1945 -1355);
FORCEPROP 2 LAST CDS_LIB mstr_misc
J 0
(-2020 -1130);
PAINT ORANGE (-2020 -1130);
DISPLAY INVISIBLE (-2020 -1130);
FORCEADD DNS..2
(-1970 -80);
PAINT RED (-1970 -80);
FORCEPROP 1 LAST COMMENT_BODY TRUE
R 1
J 0
(-1895 -305);
DISPLAY 0.872340 (-1895 -305);
PAINT GREEN (-1895 -305);
DISPLAY INVISIBLE (-1895 -305);
FORCEPROP 2 LAST CDS_LIB mstr_misc
J 0
(-1970 -80);
PAINT ORANGE (-1970 -80);
DISPLAY INVISIBLE (-1970 -80);
FORCEADD CAD_NOTE..1
(2675 2950);
FORCEPROP 1 LAST COMMENT_BODY TRUE
J 0
(2700 3050);
DISPLAY 0.978723 (2700 3050);
PAINT ORANGE (2700 3050);
DISPLAY INVISIBLE (2700 3050);
FORCEPROP 2 LAST CDS_LIB mstr_symbols
J 0
(2675 2950);
PAINT ORANGE (2675 2950);
DISPLAY INVISIBLE (2675 2950);
FORCEADD CAD_NOTE..1
(600 850);
FORCEPROP 0 LAST L1 PLACE CLOSE TO CONTROLLER
J 0
(418 758);
DISPLAY 0.617021 (418 758);
PAINT WHITE (418 758);
FORCEPROP 1 LAST COMMENT_BODY TRUE
J 0
(625 950);
DISPLAY 0.978723 (625 950);
PAINT ORANGE (625 950);
DISPLAY INVISIBLE (625 950);
FORCEPROP 2 LAST CDS_LIB mstr_symbols
J 0
(600 850);
PAINT ORANGE (600 850);
DISPLAY INVISIBLE (600 850);
FORCEADD DNS..3
(3305 -705);
PAINT RED (3305 -705);
FORCEPROP 1 LAST COMMENT_BODY TRUE
R 1
J 0
(3380 -930);
DISPLAY 0.872340 (3380 -930);
PAINT GREEN (3380 -930);
DISPLAY INVISIBLE (3380 -930);
FORCEPROP 2 LAST CDS_LIB mstr_misc
J 0
(3305 -705);
PAINT ORANGE (3305 -705);
DISPLAY INVISIBLE (3305 -705);
FORCEADD CAD_NOTE..1
(-1550 2025);
FORCEPROP 0 LAST L1 PLACE CLOSE TO CONTROLLER
J 0
(-1637 1933);
DISPLAY 0.617021 (-1637 1933);
PAINT WHITE (-1637 1933);
FORCEPROP 1 LAST COMMENT_BODY TRUE
J 0
(-1525 2125);
DISPLAY 0.978723 (-1525 2125);
PAINT ORANGE (-1525 2125);
DISPLAY INVISIBLE (-1525 2125);
FORCEPROP 2 LAST CDS_LIB mstr_symbols
J 0
(-1550 2025);
PAINT ORANGE (-1550 2025);
DISPLAY INVISIBLE (-1550 2025);
FORCEADD PRELIM..6
(-90 315);
PAINT GRAY (-90 315);
FORCEPROP 1 LAST COMMENT_BODY TRUE
J 0
(-90 315);
PAINT ORANGE (-90 315);
DISPLAY INVISIBLE (-90 315);
FORCEPROP 2 LAST CDS_LIB mstr_misc
J 0
(-90 315);
PAINT ORANGE (-90 315);
DISPLAY INVISIBLE (-90 315);
FORCEADD CAD_NOTE..1
(3075 -975);
FORCEPROP 0 LAST L2 OF PVTT PLANE
J 0
(2957 -1122);
DISPLAY 0.617021 (2957 -1122);
PAINT WHITE (2957 -1122);
FORCEPROP 0 LAST L1 PLACE NEAR CENTER
J 0
(2957 -1070);
DISPLAY 0.617021 (2957 -1070);
PAINT WHITE (2957 -1070);
FORCEPROP 1 LAST COMMENT_BODY TRUE
J 0
(3100 -875);
DISPLAY 0.978723 (3100 -875);
PAINT ORANGE (3100 -875);
DISPLAY INVISIBLE (3100 -875);
FORCEPROP 2 LAST CDS_LIB mstr_symbols
J 0
(3075 -975);
PAINT ORANGE (3075 -975);
DISPLAY INVISIBLE (3075 -975);
FORCEADD INTEL_CORP_BPAGE..1
(4300 -1825);
FORCEPROP 1 LAST CDS_CON_LAST_MODIFIED Fri Jun 16 17:49:22 2017
J 0
(2875 -1500);
PAINT GREEN (2875 -1500);
DISPLAY INVISIBLE (2875 -1500);
FORCEPROP 1 LAST CUSTOM_TXT_CDS <CURRENT_DESIGN_SHEET> OF <TOTAL_DESIGN_SHEETS>
J 0
(3800 -1800);
PAINT ORANGE (3800 -1800);
FORCEPROP 1 LAST CUSTOM_TXT_CDS <CON_LAST_MODIFIED>
J 0
(300 -1725);
PAINT ORANGE (300 -1725);
FORCEPROP 2 LAST CUSTOM_TXT_CDS <XR_PAGE_TITLE>
J 0
(-3590 3425);
DISPLAY 0.638298 (-3590 3425);
PAINT PINK (-3590 3425);
DISPLAY INVISIBLE (-3590 3425);
FORCEPROP 1 LAST SCH_TITLE DDR VTT VR CHANNEL KLM
J 0
(-3650 -1775);
DISPLAY 1.212766 (-3650 -1775);
PAINT GREEN (-3650 -1775);
FORCEPROP 2 LAST CDS_XR_PAGE_TITLE CR-230 : @BASEBOARD_FAB2_LIB.BASEBOARD_FAB2(SCH_1):PAGE230
J 0
(-3590 3425);
DISPLAY 0.638298 (-3590 3425);
PAINT PINK (-3590 3425);
DISPLAY INVISIBLE (-3590 3425);
FORCEPROP 1 LAST COMMENT_BODY TRUE
J 0
(4312 -1813);
DISPLAY 0.446809 (4312 -1813);
PAINT GREEN (4312 -1813);
DISPLAY INVISIBLE (4312 -1813);
FORCEPROP 2 LAST PAGE_BORDER TRUE
J 0
(-3590 3425);
DISPLAY 0.659574 (-3590 3425);
PAINT PINK (-3590 3425);
DISPLAY INVISIBLE (-3590 3425);
FORCEPROP 2 LAST CDS_LIB mstr_symbols
J 0
(4300 -1825);
PAINT ORANGE (4300 -1825);
DISPLAY INVISIBLE (4300 -1825);
FORCEADD CAD_NOTE..1
(3125 -500);
FORCEPROP 0 LAST L1 SPOF
J 0
(2986 -649);
DISPLAY 0.617021 (2986 -649);
PAINT WHITE (2986 -649);
FORCEPROP 1 LAST COMMENT_BODY TRUE
J 0
(3150 -400);
DISPLAY 0.978723 (3150 -400);
PAINT ORANGE (3150 -400);
DISPLAY INVISIBLE (3150 -400);
FORCEPROP 2 LAST CDS_LIB mstr_symbols
J 0
(3125 -500);
PAINT ORANGE (3125 -500);
DISPLAY INVISIBLE (3125 -500);
WIRE 16 -1 (-2025 -1300)(-2025 -1225);
WIRE 16 -1 (-1200 675)(-1200 575);
WIRE 16 -1 (350 25)(350 -100);
WIRE 16 -1 (350 125)(350 25);
WIRE 16 -1 (200 25)(350 25);
WIRE 16 -1 (350 175)(350 125);
WIRE 16 -1 (200 125)(350 125);
WIRE 16 -1 (200 175)(350 175);
WIRE 16 -1 (-1625 1525)(-1625 1425);
WIRE 16 -1 (-1200 1425)(-1200 1550);
WIRE 16 -1 (675 -100)(675 25);
WIRE 16 -1 (2325 50)(2325 -25);
WIRE 16 -1 (3125 50)(2325 50);
WIRE 16 -1 (2325 200)(2325 50);
WIRE 16 -1 (3125 225)(3125 50);
WIRE 16 -1 (2200 700)(2200 800);
WIRE 16 -1 (1350 2850)(1350 2900);
WIRE 16 -1 (1350 2850)(1750 2850);
WIRE 16 -1 (1350 2850)(1350 2775);
WIRE 16 -1 (2150 2850)(1750 2850);
WIRE 16 -1 (1750 2775)(1750 2850);
WIRE 16 -1 (2150 2775)(2150 2850);
WIRE 16 -1 (1800 1350)(1800 1500);
WIRE 16 -1 (1350 2400)(1350 2425);
WIRE 16 -1 (1350 2425)(1750 2425);
WIRE 16 -1 (1350 2575)(1350 2425);
WIRE 16 -1 (1750 2425)(2150 2425);
WIRE 16 -1 (1750 2575)(1750 2425);
WIRE 16 -1 (2150 2575)(2150 2425);
WIRE 16 -1 (3875 800)(3875 575);
WIRE 16 -1 (3875 575)(3125 575);
WIRE 16 -1 (3875 -700)(3875 575);
WIRE 16 -1 (3450 -700)(3875 -700);
WIRE 16 -1 (3125 575)(2325 575);
WIRE 16 -1 (3125 425)(3125 575);
WIRE 16 -1 (2325 400)(2325 575);
WIRE 16 -1 (200 575)(2325 575);
WIRE 16 -1 (-2050 1275)(-2050 1025);
WIRE 16 -1 (-1975 1025)(-2050 1025);
WIRE 16 -1 (-1975 25)(-1975 1025);
WIRE 16 -1 (-1625 1025)(-1975 1025);
WIRE 16 -1 (-3100 2000)(-3100 1800);
WIRE 16 -1 (-2675 1800)(-3100 1800);
WIRE 16 -1 (-2675 1800)(-2675 825);
WIRE 16 -1 (-1625 1800)(-2675 1800);
WIRE 16 -1 (-1625 1800)(-1200 1800);
WIRE 16 -1 (-1625 1725)(-1625 1800);
WIRE 16 -1 (-2450 825)(-2675 825);
WIRE 16 -1 (-1200 1800)(-575 1800);
WIRE 16 -1 (-1200 1750)(-1200 1800);
WIRE 16 -1 (-575 575)(-575 1800);
WIRE 16 -1 (-400 575)(-575 575);
WIRE 16 -1 (-1300 75)(-1300 125);
WIRE 3 682 (1650 2900)(1650 2000);
WIRE 3 682 (2450 2900)(1650 2900);
WIRE 3 682 (1650 2000)(2450 2000);
WIRE 3 682 (2450 2000)(2450 2900);
WIRE 3 682 (3650 0)(3050 0);
WIRE 3 682 (3050 0)(3050 500);
WIRE 3 682 (3650 500)(3650 0);
WIRE 3 682 (3650 500)(3050 500);
WIRE 16 2175 (-775 500)(-775 2125);
WIRE 16 2175 (-1725 2125)(-775 2125);
WIRE 16 2175 (-1725 500)(-775 500);
WIRE 16 2175 (-1725 500)(-1725 2125);
WIRE 16 2175 (1125 1900)(1125 3100);
WIRE 16 2175 (4125 3100)(1125 3100);
WIRE 16 2175 (4125 1900)(1125 1900);
WIRE 16 2175 (4125 1900)(4125 3100);
WIRE 16 273 (-550 2975)(600 2975);
WIRE 16 273 (-550 2875)(-550 2975);
WIRE 16 273 (-550 2375)(-550 2875);
WIRE 16 273 (600 2375)(-550 2375);
WIRE 16 273 (-550 2875)(600 2875);
WIRE 16 273 (600 2975)(600 2875);
WIRE 16 273 (600 2875)(600 2375);
WIRE 16 -1 (-400 225)(-750 225);
WIRE 16 -1 (-750 225)(-750 -700);
WIRE 16 -1 (3150 -700)(-750 -700);
FORCEPROP 2 LAST SIG_NAME VR_PVTT_KLM_SNS
J 0
(-710 -695);
DISPLAY 0.617021 (-710 -695);
PAINT ORANGE (-710 -695);
FORCEPROP 2 LASTPROP $XRERR UNIQUE?
J 0
(-950 -695);
DISPLAY 0.638298 (-950 -695);
PAINT MONO (-950 -695);
DISPLAY INVISIBLE (-950 -695);
WIRE 16 -1 (-2125 -600)(-2025 -600);
WIRE 16 -1 (-2025 -1025)(-2025 -600);
WIRE 16 -1 (-1975 -600)(-2025 -600);
WIRE 16 -1 (-1975 -600)(-1975 -175);
WIRE 16 -1 (-1025 -600)(-1975 -600);
WIRE 16 -1 (-1025 325)(-1025 -600);
WIRE 16 -1 (-400 325)(-1025 325);
FORCEPROP 2 LAST SIG_NAME FM_PVTT_KLM_EN_R
J 0
(-1626 -585);
DISPLAY 0.617021 (-1626 -585);
PAINT ORANGE (-1626 -585);
FORCEPROP 2 LASTPROP $XRERR UNIQUE?
J 0
(-1866 -585);
DISPLAY 0.638298 (-1866 -585);
PAINT MONO (-1866 -585);
DISPLAY INVISIBLE (-1866 -585);
WIRE 16 -1 (-2175 825)(-2250 825);
WIRE 16 -1 (-2175 425)(-2175 825);
WIRE 16 -1 (-2175 425)(-1300 425);
WIRE 16 -1 (-1300 425)(-400 425);
WIRE 16 -1 (-1300 325)(-1300 425);
FORCEPROP 2 LAST SIG_NAME VSENSE_PVDDQ_KLM_VTT
J 0
(-1882 435);
DISPLAY 0.617021 (-1882 435);
PAINT ORANGE (-1882 435);
FORCEPROP 2 LASTPROP $XRERR UNIQUE?
J 0
(-2122 435);
DISPLAY 0.638298 (-2122 435);
PAINT MONO (-2122 435);
DISPLAY INVISIBLE (-2122 435);
WIRE 16 -1 (-400 75)(-650 75);
WIRE 16 -1 (-650 75)(-650 1025);
WIRE 16 -1 (-1200 875)(-1200 1025);
WIRE 16 -1 (-650 1025)(-1200 1025);
WIRE 16 -1 (-1425 1025)(-1200 1025);
FORCEPROP 2 LAST SIG_NAME VR_PVTT_KLM_BIAS
J 0
(-1355 1045);
DISPLAY 0.617021 (-1355 1045);
PAINT ORANGE (-1355 1045);
FORCEPROP 2 LASTPROP $XRERR UNIQUE?
J 0
(-1595 1045);
DISPLAY 0.638298 (-1595 1045);
PAINT MONO (-1595 1045);
DISPLAY INVISIBLE (-1595 1045);
WIRE 16 2175 (1200 -200)(400 -200);
WIRE 16 2175 (1200 925)(1200 -200);
WIRE 16 2175 (400 -200)(400 925);
WIRE 16 2175 (400 925)(1200 925);
WIRE 16 -1 (200 275)(1800 275);
WIRE 16 -1 (1800 275)(1800 1100);
WIRE 16 -1 (1800 1150)(1800 1100);
WIRE 16 -1 (2200 1100)(1800 1100);
FORCEPROP 2 LAST SIG_NAME PWRGD_PVTT_KLM_CPU1_R
J 0
(1847 1110);
DISPLAY 0.617021 (1847 1110);
PAINT ORANGE (1847 1110);
FORCEPROP 2 LASTPROP $XRERR UNIQUE?
J 0
(1607 1110);
DISPLAY 0.638298 (1607 1110);
PAINT MONO (1607 1110);
DISPLAY INVISIBLE (1607 1110);
WIRE 16 -1 (2200 1000)(2200 1100);
WIRE 16 -1 (2475 1100)(2200 1100);
WIRE 16 -1 (3250 1100)(2675 1100);
FORCEPROP 2 LAST SIG_NAME PWRGD_PVTT_CPU1
J 0
(2772 1110);
DISPLAY 0.617021 (2772 1110);
PAINT ORANGE (2772 1110);
WIRE 3 682 (-3550 -650)(-3550 -500);
WIRE 3 682 (-2475 -650)(-3550 -650);
WIRE 3 682 (-3550 -500)(-2475 -500);
WIRE 3 682 (-2475 -500)(-2475 -650);
WIRE 16 -1 (-2325 -600)(-3025 -600);
FORCEPROP 2 LAST SIG_NAME PWRGD_PVDDQ_KLM_R
J 0
(-2975 -585);
DISPLAY 0.617021 (-2975 -585);
PAINT ORANGE (-2975 -585);
WIRE 16 -1 (675 225)(675 475);
WIRE 16 -1 (200 475)(675 475);
FORCEPROP 2 LAST SIG_NAME VR_PVTT_KLM_VREF
J 0
(256 485);
DISPLAY 0.617021 (256 485);
PAINT ORANGE (256 485);
FORCEPROP 2 LASTPROP $XRERR UNIQUE?
J 0
(16 485);
DISPLAY 0.638298 (16 485);
PAINT MONO (16 485);
DISPLAY INVISIBLE (16 485);
WIRE 16 2175 (2900 -600)(3550 -600);
WIRE 16 2175 (3550 -1175)(3550 -600);
WIRE 16 2175 (2900 -1175)(2900 -600);
WIRE 16 2175 (2900 -1175)(3550 -1175);
DOT 1 (1750 2850);
DOT 1 (1750 2425);
DOT 1 (3875 575);
DOT 1 (-2025 -600);
DOT 1 (-1975 1025);
DOT 1 (-2675 1800);
DOT 1 (-1300 425);
DOT 1 (-1200 1025);
DOT 1 (350 25);
DOT 1 (350 125);
DOT 1 (-1625 1800);
DOT 1 (-1200 1800);
DOT 1 (-550 2875);
DOT 1 (2325 50);
DOT 1 (2325 575);
DOT 1 (2200 1100);
DOT 1 (600 2875);
DOT 1 (1350 2850);
DOT 1 (3125 575);
DOT 1 (-1975 -600);
DOT 1 (1800 1100);
DOT 1 (1350 2425);
FORCENOTE
TP FAB1 CHANGE RES TO CAP 0311
(2975 -175) 0;
DISPLAY LEFT (2975 -175);
DISPLAY 1.021277 (2975 -175);
PAINT RED (2975 -175);
FORCENOTE
IOUT TDC=+/-1.4A
(-504 2556) 0;
DISPLAY LEFT (-504 2556);
DISPLAY 0.808511 (-504 2556);
PAINT PURPLE (-504 2556);
FORCENOTE
IOUT PEAK=+/-1.4A
(-504 2606) 0;
DISPLAY LEFT (-504 2606);
DISPLAY 0.808511 (-504 2606);
PAINT PURPLE (-504 2606);
FORCENOTE
PVTT DDR SPECIFICATION:
(-504 2906) 0;
DISPLAY LEFT (-504 2906);
PAINT PURPLE (-504 2906);
FORCENOTE
AC & RIPPLE=+3.5/-7.3%
(-504 2656) 0;
DISPLAY LEFT (-504 2656);
DISPLAY 0.808511 (-504 2656);
PAINT PURPLE (-504 2656);
FORCENOTE
IOUT STEP=-1.546/+1.523A
(-504 2506) 0;
DISPLAY LEFT (-504 2506);
DISPLAY 0.808511 (-504 2506);
PAINT PURPLE (-504 2506);
FORCENOTE
DC TOL= +/-1.5%
(-504 2706) 0;
DISPLAY LEFT (-504 2706);
DISPLAY 0.808511 (-504 2706);
PAINT PURPLE (-504 2706);
FORCENOTE
RIPPLE GUIDELINE= +/-1%
(-504 2756) 0;
DISPLAY LEFT (-504 2756);
DISPLAY 0.808511 (-504 2756);
PAINT PURPLE (-504 2756);
FORCENOTE
VOUT=0.5 VDDQ
(-504 2806) 0;
DISPLAY LEFT (-504 2806);
DISPLAY 0.808511 (-504 2806);
PAINT PURPLE (-504 2806);
FORCENOTE
IOUT DI/DT=6A/US
(-504 2456) 0;
DISPLAY LEFT (-504 2456);
DISPLAY 0.808511 (-504 2456);
PAINT PURPLE (-504 2456);
FORCENOTE
CRTICAL: PLACE 0 OHM NEAR  VDDQ SENSE RESISTOR.
(-3485 642) 0;
DISPLAY LEFT (-3485 642);
DISPLAY 1.021277 (-3485 642);
PAINT PURPLE (-3485 642);
FORCENOTE
ROOM = VTT_KLM_PWR_VR
(-3665 -1576) 0;
DISPLAY LEFT (-3665 -1576);
DISPLAY 1.255319 (-3665 -1576);
PAINT PURPLE (-3665 -1576);
FORCENOTE
BOM_COST = MEM_VRD_VTT_KLM
(-3665 -1651) 0;
DISPLAY LEFT (-3665 -1651);
DISPLAY 1.255319 (-3665 -1651);
PAINT PURPLE (-3665 -1651);
FORCENOTE
TP FAB1 CHANGE CONNECTION 0303
(-3550 -450) 0;
DISPLAY LEFT (-3550 -450);
DISPLAY 1.021277 (-3550 -450);
PAINT RED (-3550 -450);
FORCENOTE
PLACED BETWEEN DIMMS
(2534 2822) 0;
DISPLAY LEFT (2534 2822);
DISPLAY 1.021277 (2534 2822);
PAINT PURPLE (2534 2822);
FORCENOTE
TP FAB3 CHANGE CAP 0803
(1625 1900) 0;
DISPLAY LEFT (1625 1900);
DISPLAY 1.021277 (1625 1900);
PAINT RED (1625 1900);
QUIT
